FILE_TYPE = MACRO_DRAWING;
SET COLOR_WIRE YELLOW;
SET COLOR_PROP ORANGE;
SET COLOR_DOT WHITE;
SET COLOR_ARC YELLOW;
SET COLOR_BODY GREEN;
SET COLOR_NOTE PURPLE;
SET PROP_DISPLAY VALUE;
SET PAGE_NUMBER P273;
FORCEADD UNIVERSAL_GND..1
(3375 -1050);
FORCEPROP 3 LASTPIN (3375 -1000) SIG_NAME GND\g
J 0
(3385 -990);
DISPLAY 0.659574 (3385 -990);
PAINT MONO (3385 -990);
DISPLAY INVISIBLE (3385 -990);
FORCEPROP 2 LAST CDS_LIB logical_power
J 0
(3375 -1050);
PAINT MONO (3375 -1050);
DISPLAY INVISIBLE (3375 -1050);
FORCEPROP 1 LAST HDL_POWER GND
J 1
(3400 -1125);
DISPLAY 0.872340 (3400 -1125);
PAINT GREEN (3400 -1125);
DISPLAY INVISIBLE (3400 -1125);
FORCEPROP 1 LAST PATH I1
J 0
(3450 -1050);
DISPLAY 0.872340 (3450 -1050);
PAINT AQUA (3450 -1050);
DISPLAY INVISIBLE (3450 -1050);
FORCEADD OFFPAGE..1
(3875 2400);
FORCEPROP 2 LAST $XR6 290 
J 0
(2903 2400);
DISPLAY 0.638298 (2903 2400);
PAINT MONO (2903 2400);
FORCEPROP 2 LAST $XR5 289 
J 0
(3023 2400);
DISPLAY 0.638298 (3023 2400);
PAINT MONO (3023 2400);
FORCEPROP 2 LAST $XR4 288 
J 0
(3143 2400);
DISPLAY 0.638298 (3143 2400);
PAINT MONO (3143 2400);
FORCEPROP 2 LAST $XR3 287 
J 0
(3263 2400);
DISPLAY 0.638298 (3263 2400);
PAINT MONO (3263 2400);
FORCEPROP 2 LAST $XR2 286 
J 0
(3383 2400);
DISPLAY 0.638298 (3383 2400);
PAINT MONO (3383 2400);
FORCEPROP 2 LAST $XR1 285 
J 0
(3503 2400);
DISPLAY 0.638298 (3503 2400);
PAINT MONO (3503 2400);
FORCEPROP 2 LAST $XR0 284 
J 0
(3623 2400);
DISPLAY 0.638298 (3623 2400);
PAINT MONO (3623 2400);
FORCEPROP 1 LAST COMMENT_BODY TRUE
J 0
(4000 2300);
DISPLAY 0.872340 (4000 2300);
PAINT GREEN (4000 2300);
DISPLAY INVISIBLE (4000 2300);
FORCEPROP 1 LAST OFFPAGE TRUE
J 0
(4200 2275);
DISPLAY 0.872340 (4200 2275);
PAINT GREEN (4200 2275);
DISPLAY INVISIBLE (4200 2275);
FORCEPROP 2 LAST CDS_LIB standard
J 0
(3875 2400);
DISPLAY INVISIBLE (3875 2400);
FORCEPROP 2 LAST PATH I10
J 0
(3625 2450);
DISPLAY 1.021277 (3625 2450);
DISPLAY INVISIBLE (3625 2450);
FORCEADD OFFPAGE..5
(3850 -325);
FORCEPROP 2 LAST $XR0 284 
J 0
(3565 -325);
DISPLAY 0.638298 (3565 -325);
PAINT MONO (3565 -325);
FORCEPROP 1 LAST COMMENT_BODY TRUE
J 0
(3950 -400);
DISPLAY 0.872340 (3950 -400);
PAINT GREEN (3950 -400);
DISPLAY INVISIBLE (3950 -400);
FORCEPROP 1 LAST OFFPAGE TRUE
J 0
(4175 -450);
DISPLAY 0.872340 (4175 -450);
PAINT GREEN (4175 -450);
DISPLAY INVISIBLE (4175 -450);
FORCEPROP 2 LAST CDS_LIB standard
J 0
(3850 -325);
DISPLAY INVISIBLE (3850 -325);
FORCEPROP 2 LAST PATH I11
J 0
(3575 -275);
DISPLAY 1.021277 (3575 -275);
DISPLAY INVISIBLE (3575 -275);
FORCEADD OFFPAGE..5
(3850 -825);
FORCEPROP 2 LAST $XR4 284 
J 0
(3565 -753);
DISPLAY 0.638298 (3565 -753);
PAINT MONO (3565 -753);
FORCEPROP 2 LAST $XR3 288 
J 0
(3565 -897);
DISPLAY 0.638298 (3565 -897);
PAINT MONO (3565 -897);
FORCEPROP 2 LAST $XR2 287 
J 0
(3565 -789);
DISPLAY 0.638298 (3565 -789);
PAINT MONO (3565 -789);
FORCEPROP 2 LAST $XR1 286 
J 0
(3565 -861);
DISPLAY 0.638298 (3565 -861);
PAINT MONO (3565 -861);
FORCEPROP 2 LAST $XR0 285 
J 0
(3565 -825);
DISPLAY 0.638298 (3565 -825);
PAINT MONO (3565 -825);
FORCEPROP 1 LAST COMMENT_BODY TRUE
J 0
(3950 -900);
DISPLAY 0.872340 (3950 -900);
PAINT GREEN (3950 -900);
DISPLAY INVISIBLE (3950 -900);
FORCEPROP 1 LAST OFFPAGE TRUE
J 0
(4175 -950);
DISPLAY 0.872340 (4175 -950);
PAINT GREEN (4175 -950);
DISPLAY INVISIBLE (4175 -950);
FORCEPROP 2 LAST CDS_LIB standard
J 0
(3850 -825);
DISPLAY INVISIBLE (3850 -825);
FORCEPROP 2 LAST PATH I12
J 0
(3575 -700);
DISPLAY 1.021277 (3575 -700);
DISPLAY INVISIBLE (3575 -700);
FORCEADD OFFPAGE..5
(3875 2500);
FORCEPROP 2 LAST $XR0 284 
J 0
(3590 2500);
DISPLAY 0.638298 (3590 2500);
PAINT MONO (3590 2500);
FORCEPROP 1 LAST COMMENT_BODY TRUE
J 0
(3975 2425);
DISPLAY 0.872340 (3975 2425);
PAINT GREEN (3975 2425);
DISPLAY INVISIBLE (3975 2425);
FORCEPROP 1 LAST OFFPAGE TRUE
J 0
(4200 2375);
DISPLAY 0.872340 (4200 2375);
PAINT GREEN (4200 2375);
DISPLAY INVISIBLE (4200 2375);
FORCEPROP 2 LAST CDS_LIB standard
J 0
(3875 2500);
DISPLAY INVISIBLE (3875 2500);
FORCEPROP 2 LAST PATH I13
J 0
(3600 2550);
DISPLAY 1.021277 (3600 2550);
DISPLAY INVISIBLE (3600 2550);
FORCEADD OFFPAGE..5
(3875 2000);
FORCEPROP 2 LAST $XR4 284 
J 0
(3590 2072);
DISPLAY 0.638298 (3590 2072);
PAINT MONO (3590 2072);
FORCEPROP 2 LAST $XR3 288 
J 0
(3590 1928);
DISPLAY 0.638298 (3590 1928);
PAINT MONO (3590 1928);
FORCEPROP 2 LAST $XR2 287 
J 0
(3590 2036);
DISPLAY 0.638298 (3590 2036);
PAINT MONO (3590 2036);
FORCEPROP 2 LAST $XR1 286 
J 0
(3590 1964);
DISPLAY 0.638298 (3590 1964);
PAINT MONO (3590 1964);
FORCEPROP 2 LAST $XR0 285 
J 0
(3590 2000);
DISPLAY 0.638298 (3590 2000);
PAINT MONO (3590 2000);
FORCEPROP 1 LAST COMMENT_BODY TRUE
J 0
(3975 1925);
DISPLAY 0.872340 (3975 1925);
PAINT GREEN (3975 1925);
DISPLAY INVISIBLE (3975 1925);
FORCEPROP 1 LAST OFFPAGE TRUE
J 0
(4200 1875);
DISPLAY 0.872340 (4200 1875);
PAINT GREEN (4200 1875);
DISPLAY INVISIBLE (4200 1875);
FORCEPROP 2 LAST CDS_LIB standard
J 0
(3875 2000);
DISPLAY INVISIBLE (3875 2000);
FORCEPROP 2 LAST PATH I14
J 0
(3600 2150);
DISPLAY 1.021277 (3600 2150);
DISPLAY INVISIBLE (3600 2150);
FORCEADD Q_CAP..2
(4100 -525);
FORCEPROP 1 LAST PART_NUMBER CH4104K1B00
J 1
(4325 -500);
DISPLAY 0.617021 (4325 -500);
PAINT BLUE (4325 -500);
DISPLAY INVISIBLE (4325 -500);
FORCEPROP 1 LAST MATERIAL X7R
J 0
(4475 -500);
DISPLAY 0.617021 (4475 -500);
PAINT SKYBLUE (4475 -500);
FORCEPROP 1 LAST TOLERANCE 10%
J 2
(4625 -500);
DISPLAY 0.617021 (4625 -500);
PAINT SKYBLUE (4625 -500);
FORCEPROP 1 LAST VALUE 0.1UF
J 2
(4325 -525);
DISPLAY 0.617021 (4325 -525);
PAINT SKYBLUE (4325 -525);
FORCEPROP 1 LAST VOLTAGE 25V
J 0
(4350 -525);
DISPLAY 0.617021 (4350 -525);
PAINT SKYBLUE (4350 -525);
FORCEPROP 1 LAST PACK_TYPE 0402
J 1
(4475 -525);
DISPLAY 0.617021 (4475 -525);
PAINT SKYBLUE (4475 -525);
FORCEPROP 1 LAST LOCATION PC1360
J 1
(3900 -525);
DISPLAY 0.617021 (3900 -525);
PAINT AQUA (3900 -525);
FORCEPROP 1 LASTPIN (4000 -525) $PN 1
J 0
(3990 -510);
DISPLAY 0.617021 (3990 -510);
FORCEPROP 1 LASTPIN (4200 -525) $PN 2
J 0
(4185 -510);
DISPLAY 0.617021 (4185 -510);
FORCEPROP 2 LAST CDS_LIB pure_quanta
J 0
(4100 -525);
PAINT MONO (4100 -525);
DISPLAY INVISIBLE (4100 -525);
FORCEPROP 1 LAST PATH I15
J 0
(4100 -325);
DISPLAY 0.978723 (4100 -325);
PAINT WHITE (4100 -325);
DISPLAY INVISIBLE (4100 -325);
FORCEPROP 2 LAST $SEC 1
J 0
(4100 -275);
DISPLAY 0.680851 (4100 -275);
PAINT MONO (4100 -275);
DISPLAY INVISIBLE (4100 -275);
FORCEPROP 2 LAST CDS_SEC 1
J 0
(4100 -275);
DISPLAY 1.021277 (4100 -275);
DISPLAY INVISIBLE (4100 -275);
FORCEADD ISL99390FRZTR5935..1
(5300 -325);
FORCEPROP 1 LAST PART_NUMBER AL099390004
J 0
(5000 475);
DISPLAY 0.617021 (5000 475);
PAINT BLUE (5000 475);
DISPLAY INVISIBLE (5000 475);
FORCEPROP 2 LAST PART_TYPE SMLF
J 0
(5000 675);
DISPLAY 0.638298 (5000 675);
FORCEPROP 1 LAST MATERIAL IC
J 0
(5000 400);
DISPLAY 0.617021 (5000 400);
PAINT SKYBLUE (5000 400);
FORCEPROP 2 LAST VALUE ISL99390FRZ-TR5935
J 0
(5000 625);
DISPLAY 0.617021 (5000 625);
PAINT SKYBLUE (5000 625);
FORCEPROP 1 LAST LOCATION PU25_P1_6
J 0
(5000 550);
DISPLAY 0.617021 (5000 550);
PAINT AQUA (5000 550);
FORCEPROP 2 LASTPIN (5700 -775) $PN 2
J 0
(5710 -765);
DISPLAY 0.617021 (5710 -765);
PAINT MONO (5710 -765);
FORCEPROP 2 LASTPIN (5700 25) $PN 33
J 0
(5710 35);
DISPLAY 0.617021 (5710 35);
PAINT MONO (5710 35);
FORCEPROP 2 LASTPIN (4850 -575) $PN 31
J 2
(4840 -565);
DISPLAY 0.617021 (4840 -565);
PAINT MONO (4840 -565);
FORCEPROP 2 LASTPIN (4850 -175) $PN 35
J 2
(4840 -165);
DISPLAY 0.617021 (4840 -165);
PAINT MONO (4840 -165);
FORCEPROP 2 LASTPIN (5700 -625) $PN 6
J 0
(5710 -615);
DISPLAY 0.617021 (5710 -615);
PAINT MONO (5710 -615);
FORCEPROP 2 LASTPIN (5700 -675) $PN 41
J 0
(5710 -665);
DISPLAY 0.617021 (5710 -665);
PAINT MONO (5710 -665);
FORCEPROP 2 LASTPIN (4850 -325) $PN 38
J 2
(4840 -315);
DISPLAY 0.617021 (4840 -315);
PAINT MONO (4840 -315);
FORCEPROP 2 LASTPIN (4850 -625) $PN 37
J 2
(4840 -615);
DISPLAY 0.617021 (4840 -615);
PAINT MONO (4840 -615);
FORCEPROP 2 LASTPIN (5700 -825) $PN 5
J 0
(5710 -815);
DISPLAY 0.617021 (5710 -815);
PAINT MONO (5710 -815);
FORCEPROP 2 LASTPIN (5700 -875) $PN 7_9-20_24
J 0
(5710 -865);
DISPLAY 0.617021 (5710 -865);
PAINT MONO (5710 -865);
FORCEPROP 2 LASTPIN (5700 -925) $PN 40
J 0
(5710 -915);
DISPLAY 0.617021 (5710 -915);
PAINT MONO (5710 -915);
FORCEPROP 2 LASTPIN (5700 -225) $PN 32
J 0
(5710 -215);
DISPLAY 0.617021 (5710 -215);
PAINT MONO (5710 -215);
FORCEPROP 2 LASTPIN (4850 325) $PN 4
J 2
(4840 335);
DISPLAY 0.617021 (4840 335);
PAINT MONO (4840 335);
FORCEPROP 2 LASTPIN (4850 -925) $PN 34
J 2
(4840 -915);
DISPLAY 0.617021 (4840 -915);
PAINT MONO (4840 -915);
FORCEPROP 2 LASTPIN (4850 -425) $PN 39
J 2
(4840 -415);
DISPLAY 0.617021 (4840 -415);
PAINT MONO (4840 -415);
FORCEPROP 2 LASTPIN (5700 -325) $PN 10_19
J 0
(5710 -315);
DISPLAY 0.617021 (5710 -315);
PAINT MONO (5710 -315);
FORCEPROP 2 LASTPIN (4850 -825) $PN 36
J 2
(4840 -815);
DISPLAY 0.617021 (4840 -815);
PAINT MONO (4840 -815);
FORCEPROP 2 LASTPIN (4850 25) $PN 3
J 2
(4840 35);
DISPLAY 0.617021 (4840 35);
PAINT MONO (4840 35);
FORCEPROP 2 LASTPIN (5700 325) $PN 25_29
J 0
(5710 335);
DISPLAY 0.617021 (5710 335);
PAINT MONO (5710 335);
FORCEPROP 2 LASTPIN (5700 275) $PN 30
J 0
(5710 285);
DISPLAY 0.617021 (5710 285);
PAINT MONO (5710 285);
FORCEPROP 2 LASTPIN (5700 -575) $PN 1
J 0
(5710 -565);
DISPLAY 0.617021 (5710 -565);
PAINT MONO (5710 -565);
FORCEPROP 1 LAST NEEDS_NO_SIZE TRUE
J 0
(5300 -325);
DISPLAY 0.723404 (5300 -325);
PAINT GREEN (5300 -325);
DISPLAY INVISIBLE (5300 -325);
FORCEPROP 1 LAST CDS_LMAN_SYM_OUTLINE -300,700,250,-650
J 0
(5300 -325);
DISPLAY 0.468085 (5300 -325);
PAINT GREEN (5300 -325);
DISPLAY INVISIBLE (5300 -325);
FORCEPROP 2 LAST CDS_LIB pure_quanta
J 0
(5300 -325);
DISPLAY INVISIBLE (5300 -325);
FORCEPROP 1 LAST PATH I16
J 0
(5300 -325);
DISPLAY 0.723404 (5300 -325);
PAINT GREEN (5300 -325);
DISPLAY INVISIBLE (5300 -325);
FORCEPROP 2 LAST $SEC 1
J 0
(5000 600);
DISPLAY 0.680851 (5000 600);
PAINT MONO (5000 600);
DISPLAY INVISIBLE (5000 600);
FORCEPROP 2 LAST CDS_SEC 1
J 0
(5000 600);
DISPLAY 1.021277 (5000 600);
DISPLAY INVISIBLE (5000 600);
FORCEADD Q_CAP..1
(3775 175);
FORCEPROP 1 LAST PART_NUMBER CH5222KEB01
J 0
(3825 0);
DISPLAY 0.617021 (3825 0);
PAINT BLUE (3825 0);
DISPLAY INVISIBLE (3825 0);
FORCEPROP 1 LAST MATERIAL X6S
J 0
(3825 100);
DISPLAY 0.617021 (3825 100);
PAINT SKYBLUE (3825 100);
FORCEPROP 1 LAST TOLERANCE 10%
J 0
(3825 150);
DISPLAY 0.617021 (3825 150);
PAINT SKYBLUE (3825 150);
FORCEPROP 1 LAST VALUE 2.2UF
J 0
(3825 250);
DISPLAY 0.617021 (3825 250);
PAINT SKYBLUE (3825 250);
FORCEPROP 1 LAST VOLTAGE 10V
J 0
(3825 200);
DISPLAY 0.617021 (3825 200);
PAINT SKYBLUE (3825 200);
FORCEPROP 1 LAST PACK_TYPE C0402
J 0
(3825 50);
DISPLAY 0.617021 (3825 50);
PAINT SKYBLUE (3825 50);
FORCEPROP 1 LAST LOCATION PC501
J 0
(3825 300);
DISPLAY 0.617021 (3825 300);
PAINT AQUA (3825 300);
FORCEPROP 1 LASTPIN (3775 275) $PN 1
J 0
(3785 255);
DISPLAY 0.617021 (3785 255);
PAINT MONO (3785 255);
FORCEPROP 1 LASTPIN (3775 75) $PN 2
J 0
(3785 55);
DISPLAY 0.617021 (3785 55);
PAINT MONO (3785 55);
FORCEPROP 2 LAST CDS_LIB pure_quanta
J 0
(3775 175);
DISPLAY INVISIBLE (3775 175);
FORCEPROP 1 LAST PATH I17
J 0
(3825 325);
DISPLAY 0.978723 (3825 325);
PAINT WHITE (3825 325);
DISPLAY INVISIBLE (3825 325);
FORCEPROP 1 LAST LOCATION PC501
J 0
(3825 350);
DISPLAY 1.021277 (3825 350);
PAINT AQUA (3825 350);
DISPLAY INVISIBLE (3825 350);
FORCEPROP 0 LAST $SEC 1
J 0
(3825 350);
DISPLAY 0.680851 (3825 350);
PAINT MONO (3825 350);
DISPLAY INVISIBLE (3825 350);
FORCEPROP 0 LAST CDS_SEC 1
J 0
(3825 350);
DISPLAY 1.021277 (3825 350);
DISPLAY INVISIBLE (3825 350);
FORCEADD UNIVERSAL_GND..1
(3775 -75);
FORCEPROP 3 LASTPIN (3775 -25) SIG_NAME GND\g
J 0
(3785 -15);
DISPLAY 0.659574 (3785 -15);
PAINT MONO (3785 -15);
DISPLAY INVISIBLE (3785 -15);
FORCEPROP 2 LAST CDS_LIB logical_power
J 0
(3775 -75);
PAINT MONO (3775 -75);
DISPLAY INVISIBLE (3775 -75);
FORCEPROP 1 LAST HDL_POWER GND
J 1
(3800 -150);
DISPLAY 0.872340 (3800 -150);
PAINT GREEN (3800 -150);
DISPLAY INVISIBLE (3800 -150);
FORCEPROP 1 LAST PATH I18
J 0
(3850 -75);
DISPLAY 0.872340 (3850 -75);
PAINT AQUA (3850 -75);
DISPLAY INVISIBLE (3850 -75);
FORCEADD Q_RES..2
(3775 675);
FORCEPROP 1 LAST PART_NUMBER CS-2202FB01
J 0
(3815 550);
DISPLAY 0.617021 (3815 550);
PAINT BLUE (3815 550);
DISPLAY INVISIBLE (3815 550);
FORCEPROP 1 LAST WATTAGE 1/16W
J 0
(3815 650);
DISPLAY 0.617021 (3815 650);
PAINT SKYBLUE (3815 650);
FORCEPROP 1 LAST MATERIAL CHIP
J 0
(3815 600);
DISPLAY 0.617021 (3815 600);
PAINT SKYBLUE (3815 600);
FORCEPROP 1 LAST TOLERANCE 1%
J 0
(3820 700);
DISPLAY 0.617021 (3820 700);
PAINT SKYBLUE (3820 700);
FORCEPROP 1 LAST VALUE 2.2
J 0
(3820 750);
DISPLAY 0.617021 (3820 750);
PAINT SKYBLUE (3820 750);
FORCEPROP 1 LAST PACK_TYPE 0402LF
J 0
(3815 500);
DISPLAY 0.617021 (3815 500);
PAINT SKYBLUE (3815 500);
FORCEPROP 1 LAST LOCATION PR293
J 0
(3820 800);
DISPLAY 0.617021 (3820 800);
PAINT AQUA (3820 800);
FORCEPROP 1 LASTPIN (3775 775) $PN 1
J 0
(3780 737);
DISPLAY 0.617021 (3780 737);
PAINT MONO (3780 737);
FORCEPROP 1 LASTPIN (3775 575) $PN 2
J 0
(3780 585);
DISPLAY 0.617021 (3780 585);
PAINT MONO (3780 585);
FORCEPROP 2 LAST CDS_LIB pure_quanta
J 0
(3775 675);
DISPLAY INVISIBLE (3775 675);
FORCEPROP 1 LAST PATH I19
J 0
(3825 850);
DISPLAY 0.978723 (3825 850);
PAINT WHITE (3825 850);
DISPLAY INVISIBLE (3825 850);
FORCEPROP 1 LAST LOCATION PR293
J 0
(3825 850);
DISPLAY 1.021277 (3825 850);
PAINT AQUA (3825 850);
DISPLAY INVISIBLE (3825 850);
FORCEPROP 0 LAST $SEC 1
J 0
(3825 850);
DISPLAY 0.680851 (3825 850);
PAINT MONO (3825 850);
DISPLAY INVISIBLE (3825 850);
FORCEPROP 0 LAST CDS_SEC 1
J 0
(3825 850);
DISPLAY 1.021277 (3825 850);
DISPLAY INVISIBLE (3825 850);
FORCEADD Q_RES..2
R 2
(3375 -825);
FORCEPROP 1 LAST PART_NUMBER CS28872FB01
J 2
(3325 -950);
DISPLAY 0.617021 (3325 -950);
PAINT BLUE (3325 -950);
DISPLAY INVISIBLE (3325 -950);
FORCEPROP 1 LAST WATTAGE 1/16W
J 2
(3325 -850);
DISPLAY 0.617021 (3325 -850);
PAINT SKYBLUE (3325 -850);
FORCEPROP 1 LAST MATERIAL EMPTY
J 2
(3325 -900);
DISPLAY 0.617021 (3325 -900);
PAINT RED (3325 -900);
FORCEPROP 1 LAST TOLERANCE 1%
J 2
(3320 -800);
DISPLAY 0.617021 (3320 -800);
PAINT SKYBLUE (3320 -800);
FORCEPROP 1 LAST VALUE 8.87K
J 2
(3320 -750);
DISPLAY 0.617021 (3320 -750);
PAINT SKYBLUE (3320 -750);
FORCEPROP 1 LAST PACK_TYPE 0402LF
J 2
(3325 -1000);
DISPLAY 0.617021 (3325 -1000);
PAINT SKYBLUE (3325 -1000);
FORCEPROP 1 LAST LOCATION PR291
J 2
(3330 -700);
DISPLAY 0.617021 (3330 -700);
PAINT AQUA (3330 -700);
FORCEPROP 1 LASTPIN (3375 -725) $PN 1
J 2
(3370 -763);
DISPLAY 0.617021 (3370 -763);
PAINT MONO (3370 -763);
FORCEPROP 1 LASTPIN (3375 -925) $PN 2
J 2
(3370 -915);
DISPLAY 0.617021 (3370 -915);
PAINT MONO (3370 -915);
FORCEPROP 2 LAST CDS_LIB pure_quanta
J 2
(3375 -825);
DISPLAY INVISIBLE (3375 -825);
FORCEPROP 1 LAST PATH I2
J 2
(3325 -650);
DISPLAY 0.978723 (3325 -650);
PAINT WHITE (3325 -650);
DISPLAY INVISIBLE (3325 -650);
FORCEPROP 1 LAST LOCATION PR291
J 2
(3325 -650);
DISPLAY 1.021277 (3325 -650);
PAINT AQUA (3325 -650);
DISPLAY INVISIBLE (3325 -650);
FORCEPROP 0 LAST $SEC 1
J 2
(3325 -650);
DISPLAY 0.680851 (3325 -650);
PAINT MONO (3325 -650);
DISPLAY INVISIBLE (3325 -650);
FORCEPROP 0 LAST CDS_SEC 1
J 2
(3325 -650);
DISPLAY 1.021277 (3325 -650);
DISPLAY INVISIBLE (3325 -650);
FORCEADD UNIVERSAL_GND..1
(4200 450);
FORCEPROP 3 LASTPIN (4200 500) SIG_NAME GND\g
J 0
(4210 510);
DISPLAY 0.659574 (4210 510);
PAINT MONO (4210 510);
DISPLAY INVISIBLE (4210 510);
FORCEPROP 2 LAST CDS_LIB logical_power
J 0
(4200 450);
PAINT MONO (4200 450);
DISPLAY INVISIBLE (4200 450);
FORCEPROP 1 LAST HDL_POWER GND
J 1
(4225 375);
DISPLAY 0.872340 (4225 375);
PAINT GREEN (4225 375);
DISPLAY INVISIBLE (4225 375);
FORCEPROP 1 LAST PATH I20
J 0
(4275 450);
DISPLAY 0.872340 (4275 450);
PAINT AQUA (4275 450);
DISPLAY INVISIBLE (4275 450);
FORCEADD Q_CAP..1
(4200 675);
FORCEPROP 1 LAST PART_NUMBER CH5222KEB01
J 0
(4250 550);
DISPLAY 0.617021 (4250 550);
PAINT BLUE (4250 550);
DISPLAY INVISIBLE (4250 550);
FORCEPROP 1 LAST MATERIAL X6S
J 0
(4250 600);
DISPLAY 0.617021 (4250 600);
PAINT SKYBLUE (4250 600);
FORCEPROP 1 LAST TOLERANCE 10%
J 0
(4250 650);
DISPLAY 0.617021 (4250 650);
PAINT SKYBLUE (4250 650);
FORCEPROP 1 LAST VALUE 2.2UF
J 0
(4250 750);
DISPLAY 0.617021 (4250 750);
PAINT SKYBLUE (4250 750);
FORCEPROP 1 LAST VOLTAGE 10V
J 0
(4250 700);
DISPLAY 0.617021 (4250 700);
PAINT SKYBLUE (4250 700);
FORCEPROP 1 LAST PACK_TYPE C0402
J 0
(4250 500);
DISPLAY 0.617021 (4250 500);
PAINT SKYBLUE (4250 500);
FORCEPROP 1 LAST LOCATION PC503_P1_6
J 0
(4250 800);
DISPLAY 0.617021 (4250 800);
PAINT AQUA (4250 800);
FORCEPROP 1 LASTPIN (4200 775) $PN 1
J 0
(4210 755);
DISPLAY 0.617021 (4210 755);
PAINT MONO (4210 755);
FORCEPROP 1 LASTPIN (4200 575) $PN 2
J 0
(4210 555);
DISPLAY 0.617021 (4210 555);
PAINT MONO (4210 555);
FORCEPROP 2 LAST CDS_LIB pure_quanta
J 0
(4200 675);
DISPLAY INVISIBLE (4200 675);
FORCEPROP 1 LAST PATH I21
J 0
(4250 825);
DISPLAY 0.978723 (4250 825);
PAINT WHITE (4250 825);
DISPLAY INVISIBLE (4250 825);
FORCEPROP 1 LAST LOCATION PC503_P1_6
J 0
(4250 850);
DISPLAY 1.021277 (4250 850);
PAINT AQUA (4250 850);
DISPLAY INVISIBLE (4250 850);
FORCEPROP 0 LAST $SEC 1
J 0
(4250 850);
DISPLAY 0.680851 (4250 850);
PAINT MONO (4250 850);
DISPLAY INVISIBLE (4250 850);
FORCEPROP 0 LAST CDS_SEC 1
J 0
(4250 850);
DISPLAY 1.021277 (4250 850);
DISPLAY INVISIBLE (4250 850);
FORCEADD VCC15..1
(3775 1000);
FORCEPROP 3 LASTPIN (3775 950) SIG_NAME PVCCIN_CPU1_PVCC\g
J 0
(3785 960);
DISPLAY 0.659574 (3785 960);
PAINT MONO (3785 960);
DISPLAY INVISIBLE (3785 960);
FORCEPROP 1 LAST HDL_POWER PVCCIN_CPU1_PVCC
J 1
(3775 1050);
DISPLAY 0.617021 (3775 1050);
PAINT GREEN (3775 1050);
FORCEPROP 2 LAST CDS_LIB logical_power
J 0
(3775 1000);
DISPLAY INVISIBLE (3775 1000);
FORCEPROP 1 LAST PATH I22
J 0
(3825 1025);
DISPLAY 0.872340 (3825 1025);
PAINT AQUA (3825 1025);
DISPLAY INVISIBLE (3825 1025);
FORCEADD ISL99390FRZTR5935..1
(5325 2500);
FORCEPROP 1 LAST PART_NUMBER AL099390004
J 0
(5025 3300);
DISPLAY 0.617021 (5025 3300);
PAINT BLUE (5025 3300);
DISPLAY INVISIBLE (5025 3300);
FORCEPROP 2 LAST PART_TYPE SMLF
J 0
(5025 3500);
DISPLAY 0.638298 (5025 3500);
FORCEPROP 1 LAST MATERIAL IC
J 0
(5025 3225);
DISPLAY 0.617021 (5025 3225);
PAINT SKYBLUE (5025 3225);
FORCEPROP 2 LAST VALUE ISL99390FRZ-TR5935
J 0
(5025 3450);
DISPLAY 0.617021 (5025 3450);
PAINT SKYBLUE (5025 3450);
FORCEPROP 1 LAST LOCATION PU26_P1_5
J 0
(5025 3375);
DISPLAY 0.617021 (5025 3375);
PAINT AQUA (5025 3375);
FORCEPROP 2 LASTPIN (5725 2050) $PN 2
J 0
(5735 2060);
DISPLAY 0.617021 (5735 2060);
PAINT MONO (5735 2060);
FORCEPROP 2 LASTPIN (5725 2850) $PN 33
J 0
(5735 2860);
DISPLAY 0.617021 (5735 2860);
PAINT MONO (5735 2860);
FORCEPROP 2 LASTPIN (4875 2250) $PN 31
J 2
(4865 2260);
DISPLAY 0.617021 (4865 2260);
PAINT MONO (4865 2260);
FORCEPROP 2 LASTPIN (4875 2650) $PN 35
J 2
(4865 2660);
DISPLAY 0.617021 (4865 2660);
PAINT MONO (4865 2660);
FORCEPROP 2 LASTPIN (5725 2200) $PN 6
J 0
(5735 2210);
DISPLAY 0.617021 (5735 2210);
PAINT MONO (5735 2210);
FORCEPROP 2 LASTPIN (5725 2150) $PN 41
J 0
(5735 2160);
DISPLAY 0.617021 (5735 2160);
PAINT MONO (5735 2160);
FORCEPROP 2 LASTPIN (4875 2500) $PN 38
J 2
(4865 2510);
DISPLAY 0.617021 (4865 2510);
PAINT MONO (4865 2510);
FORCEPROP 2 LASTPIN (4875 2200) $PN 37
J 2
(4865 2210);
DISPLAY 0.617021 (4865 2210);
PAINT MONO (4865 2210);
FORCEPROP 2 LASTPIN (5725 2000) $PN 5
J 0
(5735 2010);
DISPLAY 0.617021 (5735 2010);
PAINT MONO (5735 2010);
FORCEPROP 2 LASTPIN (5725 1950) $PN 7_9-20_24
J 0
(5735 1960);
DISPLAY 0.617021 (5735 1960);
PAINT MONO (5735 1960);
FORCEPROP 2 LASTPIN (5725 1900) $PN 40
J 0
(5735 1910);
DISPLAY 0.617021 (5735 1910);
PAINT MONO (5735 1910);
FORCEPROP 2 LASTPIN (5725 2600) $PN 32
J 0
(5735 2610);
DISPLAY 0.617021 (5735 2610);
PAINT MONO (5735 2610);
FORCEPROP 2 LASTPIN (4875 3150) $PN 4
J 2
(4865 3160);
DISPLAY 0.617021 (4865 3160);
PAINT MONO (4865 3160);
FORCEPROP 2 LASTPIN (4875 1900) $PN 34
J 2
(4865 1910);
DISPLAY 0.617021 (4865 1910);
PAINT MONO (4865 1910);
FORCEPROP 2 LASTPIN (4875 2400) $PN 39
J 2
(4865 2410);
DISPLAY 0.617021 (4865 2410);
PAINT MONO (4865 2410);
FORCEPROP 2 LASTPIN (5725 2500) $PN 10_19
J 0
(5735 2510);
DISPLAY 0.617021 (5735 2510);
PAINT MONO (5735 2510);
FORCEPROP 2 LASTPIN (4875 2000) $PN 36
J 2
(4865 2010);
DISPLAY 0.617021 (4865 2010);
PAINT MONO (4865 2010);
FORCEPROP 2 LASTPIN (4875 2850) $PN 3
J 2
(4865 2860);
DISPLAY 0.617021 (4865 2860);
PAINT MONO (4865 2860);
FORCEPROP 2 LASTPIN (5725 3150) $PN 25_29
J 0
(5735 3160);
DISPLAY 0.617021 (5735 3160);
PAINT MONO (5735 3160);
FORCEPROP 2 LASTPIN (5725 3100) $PN 30
J 0
(5735 3110);
DISPLAY 0.617021 (5735 3110);
PAINT MONO (5735 3110);
FORCEPROP 2 LASTPIN (5725 2250) $PN 1
J 0
(5735 2260);
DISPLAY 0.617021 (5735 2260);
PAINT MONO (5735 2260);
FORCEPROP 1 LAST NEEDS_NO_SIZE TRUE
J 0
(5325 2500);
DISPLAY 0.723404 (5325 2500);
PAINT GREEN (5325 2500);
DISPLAY INVISIBLE (5325 2500);
FORCEPROP 1 LAST CDS_LMAN_SYM_OUTLINE -300,700,250,-650
J 0
(5325 2500);
DISPLAY 0.468085 (5325 2500);
PAINT GREEN (5325 2500);
DISPLAY INVISIBLE (5325 2500);
FORCEPROP 2 LAST CDS_LIB pure_quanta
J 0
(5325 2500);
DISPLAY INVISIBLE (5325 2500);
FORCEPROP 1 LAST PATH I23
J 0
(5325 2500);
DISPLAY 0.723404 (5325 2500);
PAINT GREEN (5325 2500);
DISPLAY INVISIBLE (5325 2500);
FORCEPROP 2 LAST $SEC 1
J 0
(5025 3425);
DISPLAY 0.680851 (5025 3425);
PAINT MONO (5025 3425);
DISPLAY INVISIBLE (5025 3425);
FORCEPROP 2 LAST CDS_SEC 1
J 0
(5025 3425);
DISPLAY 1.021277 (5025 3425);
DISPLAY INVISIBLE (5025 3425);
FORCEADD UNIVERSAL_GND..1
(5950 -1050);
FORCEPROP 3 LASTPIN (5950 -1000) SIG_NAME GND\g
J 0
(5960 -990);
DISPLAY 0.659574 (5960 -990);
PAINT MONO (5960 -990);
DISPLAY INVISIBLE (5960 -990);
FORCEPROP 2 LAST CDS_LIB logical_power
J 0
(5950 -1050);
PAINT MONO (5950 -1050);
DISPLAY INVISIBLE (5950 -1050);
FORCEPROP 1 LAST HDL_POWER GND
J 1
(5975 -1125);
DISPLAY 0.872340 (5975 -1125);
PAINT GREEN (5975 -1125);
DISPLAY INVISIBLE (5975 -1125);
FORCEPROP 1 LAST PATH I24
J 0
(6025 -1050);
DISPLAY 0.872340 (6025 -1050);
PAINT AQUA (6025 -1050);
DISPLAY INVISIBLE (6025 -1050);
FORCEADD OFFPAGE..6
(6550 -575);
FORCEPROP 2 LAST $XR0 285 
J 0
(6270 -575);
DISPLAY 0.638298 (6270 -575);
PAINT MONO (6270 -575);
FORCEPROP 1 LAST COMMENT_BODY TRUE
J 0
(6650 -650);
DISPLAY 0.872340 (6650 -650);
PAINT GREEN (6650 -650);
DISPLAY INVISIBLE (6650 -650);
FORCEPROP 1 LAST OFFPAGE TRUE
J 0
(6875 -700);
DISPLAY 0.872340 (6875 -700);
PAINT GREEN (6875 -700);
DISPLAY INVISIBLE (6875 -700);
FORCEPROP 2 LAST CDS_LIB standard
J 0
(6550 -575);
DISPLAY INVISIBLE (6550 -575);
FORCEPROP 2 LAST PATH I25
J 0
(6275 -525);
DISPLAY 1.021277 (6275 -525);
DISPLAY INVISIBLE (6275 -525);
FORCEADD Q_CAP..1
R 2
(7275 -50);
FORCEPROP 1 LAST PART_NUMBER CH4106K1B01
J 2
(7225 -125);
DISPLAY 0.617021 (7225 -125);
PAINT BLUE (7225 -125);
DISPLAY INVISIBLE (7225 -125);
FORCEPROP 1 LAST MATERIAL X7R
J 2
(7225 -100);
DISPLAY 0.617021 (7225 -100);
PAINT SKYBLUE (7225 -100);
FORCEPROP 1 LAST TOLERANCE 10%
J 2
(7225 -75);
DISPLAY 0.617021 (7225 -75);
PAINT SKYBLUE (7225 -75);
FORCEPROP 1 LAST VALUE 100NF
J 2
(7225 -25);
DISPLAY 0.617021 (7225 -25);
PAINT SKYBLUE (7225 -25);
FORCEPROP 1 LAST VOLTAGE 50V
J 2
(7225 -50);
DISPLAY 0.617021 (7225 -50);
PAINT SKYBLUE (7225 -50);
FORCEPROP 1 LAST PACK_TYPE C0402
J 2
(7225 -150);
DISPLAY 0.617021 (7225 -150);
PAINT SKYBLUE (7225 -150);
FORCEPROP 1 LAST LOCATION PC509
J 2
(7225 25);
DISPLAY 0.617021 (7225 25);
PAINT AQUA (7225 25);
FORCEPROP 1 LASTPIN (7275 50) $PN 1
J 2
(7265 30);
DISPLAY 0.617021 (7265 30);
FORCEPROP 1 LASTPIN (7275 -150) $PN 2
J 2
(7265 -170);
DISPLAY 0.617021 (7265 -170);
FORCEPROP 2 LAST CDS_LIB pure_quanta
J 2
(7275 -50);
PAINT MONO (7275 -50);
DISPLAY INVISIBLE (7275 -50);
FORCEPROP 1 LAST PATH I26
J 2
(7225 100);
DISPLAY 0.978723 (7225 100);
PAINT WHITE (7225 100);
DISPLAY INVISIBLE (7225 100);
FORCEPROP 2 LAST $SEC 1
J 0
(7225 150);
DISPLAY 0.680851 (7225 150);
PAINT MONO (7225 150);
DISPLAY INVISIBLE (7225 150);
FORCEPROP 2 LAST CDS_SEC 1
J 0
(7225 150);
DISPLAY 1.021277 (7225 150);
DISPLAY INVISIBLE (7225 150);
FORCEADD Q_RES..1
(7850 -900);
FORCEPROP 1 LAST PART_NUMBER CS00002JB13
J 0
(7725 -850);
DISPLAY 0.617021 (7725 -850);
PAINT BLUE (7725 -850);
DISPLAY INVISIBLE (7725 -850);
FORCEPROP 1 LAST WATTAGE 1/16W
J 2
(8100 -800);
DISPLAY 0.617021 (8100 -800);
PAINT SKYBLUE (8100 -800);
FORCEPROP 1 LAST MATERIAL CHIP
J 0
(8125 -900);
DISPLAY 0.617021 (8125 -900);
PAINT SKYBLUE (8125 -900);
FORCEPROP 1 LAST TOLERANCE 5%
J 0
(8050 -900);
DISPLAY 0.617021 (8050 -900);
PAINT SKYBLUE (8050 -900);
FORCEPROP 1 LAST VALUE 0
J 2
(8025 -900);
DISPLAY 0.617021 (8025 -900);
PAINT SKYBLUE (8025 -900);
FORCEPROP 1 LAST PACK_TYPE 0402LF
J 0
(7725 -800);
DISPLAY 0.617021 (7725 -800);
PAINT SKYBLUE (7725 -800);
FORCEPROP 1 LAST LOCATION PR295
J 0
(7575 -900);
DISPLAY 0.617021 (7575 -900);
PAINT AQUA (7575 -900);
FORCEPROP 1 LASTPIN (7750 -900) $PN 1
J 0
(7762 -888);
DISPLAY 0.617021 (7762 -888);
PAINT MONO (7762 -888);
FORCEPROP 1 LASTPIN (7950 -900) $PN 2
J 0
(7912 -888);
DISPLAY 0.617021 (7912 -888);
PAINT MONO (7912 -888);
FORCEPROP 2 LAST CDS_LIB pure_quanta
J 0
(7850 -900);
DISPLAY INVISIBLE (7850 -900);
FORCEPROP 1 LAST PATH I27
J 0
(7800 -750);
DISPLAY 0.978723 (7800 -750);
PAINT WHITE (7800 -750);
DISPLAY INVISIBLE (7800 -750);
FORCEPROP 0 LAST $SEC 1
J 0
(8100 -750);
DISPLAY 0.680851 (8100 -750);
PAINT MONO (8100 -750);
DISPLAY INVISIBLE (8100 -750);
FORCEPROP 0 LAST CDS_SEC 1
J 0
(8100 -750);
DISPLAY 1.021277 (8100 -750);
DISPLAY INVISIBLE (8100 -750);
FORCEADD Q_INDUCTOR4P_14..1
(7800 -450);
FORCEPROP 1 LAST PART_NUMBER CV+15^0TZ04
J 0
(7575 -290);
DISPLAY 0.617021 (7575 -290);
PAINT BLUE (7575 -290);
DISPLAY INVISIBLE (7575 -290);
FORCEPROP 2 LAST VALUE 150NH
J 0
(7575 -150);
DISPLAY 0.617021 (7575 -150);
PAINT SKYBLUE (7575 -150);
FORCEPROP 1 LAST MATERIAL IND
J 0
(7575 -240);
DISPLAY 0.617021 (7575 -240);
PAINT SKYBLUE (7575 -240);
FORCEPROP 2 LAST PART_TYPE SMLF
J 0
(7575 -100);
DISPLAY 1.021277 (7575 -100);
FORCEPROP 1 LAST LOCATION PL26
J 0
(7575 -195);
DISPLAY 0.617021 (7575 -195);
PAINT AQUA (7575 -195);
FORCEPROP 2 LASTPIN (7400 -325) $PN 1
J 2
(7390 -315);
DISPLAY 0.617021 (7390 -315);
PAINT MONO (7390 -315);
FORCEPROP 2 LASTPIN (7400 -575) $PN 2
J 2
(7390 -565);
DISPLAY 0.617021 (7390 -565);
PAINT MONO (7390 -565);
FORCEPROP 2 LASTPIN (8200 -575) $PN 3
J 0
(8210 -565);
DISPLAY 0.617021 (8210 -565);
PAINT MONO (8210 -565);
FORCEPROP 2 LASTPIN (8200 -325) $PN 4
J 0
(8210 -315);
DISPLAY 0.617021 (8210 -315);
PAINT MONO (8210 -315);
FORCEPROP 2 LAST SEC_TYPE 
J 0
(7575 -50);
DISPLAY 1.021277 (7575 -50);
DISPLAY INVISIBLE (7575 -50);
FORCEPROP 2 LAST CDS_LIB pure_quanta
J 0
(7800 -450);
DISPLAY INVISIBLE (7800 -450);
FORCEPROP 1 LAST NEEDS_NO_SIZE TRUE
J 0
(7800 -450);
DISPLAY 0.468085 (7800 -450);
PAINT GREEN (7800 -450);
DISPLAY INVISIBLE (7800 -450);
FORCEPROP 1 LAST PATH I28
J 0
(8000 -295);
DISPLAY 0.723404 (8000 -295);
PAINT GREEN (8000 -295);
DISPLAY INVISIBLE (8000 -295);
FORCEPROP 2 LAST SEC 1
J 0
(7575 -50);
DISPLAY 0.680851 (7575 -50);
PAINT MONO (7575 -50);
DISPLAY INVISIBLE (7575 -50);
FORCEADD Q_CAP..1
(6100 575);
FORCEPROP 1 LAST PART_NUMBER TMP_QCH2336K1B12
J 0
(6150 425);
DISPLAY 0.617021 (6150 425);
PAINT BLUE (6150 425);
DISPLAY INVISIBLE (6150 425);
FORCEPROP 1 LAST MATERIAL X7R
J 0
(6150 525);
DISPLAY 0.617021 (6150 525);
PAINT SKYBLUE (6150 525);
FORCEPROP 1 LAST TOLERANCE 10%
J 0
(6150 575);
DISPLAY 0.617021 (6150 575);
PAINT SKYBLUE (6150 575);
FORCEPROP 1 LAST VALUE 3300PF
J 0
(6150 675);
DISPLAY 0.617021 (6150 675);
PAINT SKYBLUE (6150 675);
FORCEPROP 1 LAST VOLTAGE 50V
J 0
(6150 625);
DISPLAY 0.617021 (6150 625);
PAINT SKYBLUE (6150 625);
FORCEPROP 1 LAST PACK_TYPE 0402
J 0
(6150 475);
DISPLAY 0.617021 (6150 475);
PAINT SKYBLUE (6150 475);
FORCEPROP 1 LAST LOCATION PC505_P1_6
J 0
(6150 725);
DISPLAY 0.617021 (6150 725);
PAINT AQUA (6150 725);
FORCEPROP 1 LASTPIN (6100 675) $PN 1
J 0
(6110 655);
DISPLAY 0.617021 (6110 655);
PAINT MONO (6110 655);
FORCEPROP 1 LASTPIN (6100 475) $PN 2
J 0
(6110 455);
DISPLAY 0.617021 (6110 455);
PAINT MONO (6110 455);
FORCEPROP 2 LAST CDS_LIB pure_quanta
J 0
(6100 575);
DISPLAY INVISIBLE (6100 575);
FORCEPROP 1 LAST PATH I29
J 0
(6150 725);
DISPLAY 0.978723 (6150 725);
PAINT WHITE (6150 725);
DISPLAY INVISIBLE (6150 725);
FORCEPROP 1 LAST LOCATION PC505_P1_6
J 0
(6150 775);
DISPLAY 1.021277 (6150 775);
PAINT AQUA (6150 775);
DISPLAY INVISIBLE (6150 775);
FORCEPROP 0 LAST $SEC 1
J 0
(6150 775);
DISPLAY 0.680851 (6150 775);
PAINT MONO (6150 775);
DISPLAY INVISIBLE (6150 775);
FORCEPROP 0 LAST CDS_SEC 1
J 0
(6150 775);
DISPLAY 1.021277 (6150 775);
DISPLAY INVISIBLE (6150 775);
FORCEADD OFFPAGE..1
(3850 -925);
FORCEPROP 2 LAST $XR0 284 
J 0
(3424 -925);
DISPLAY 0.638298 (3424 -925);
PAINT MONO (3424 -925);
FORCEPROP 1 LAST COMMENT_BODY TRUE
J 0
(3975 -1025);
DISPLAY 0.872340 (3975 -1025);
PAINT GREEN (3975 -1025);
DISPLAY INVISIBLE (3975 -1025);
FORCEPROP 1 LAST OFFPAGE TRUE
J 0
(4175 -1050);
DISPLAY 0.872340 (4175 -1050);
PAINT GREEN (4175 -1050);
DISPLAY INVISIBLE (4175 -1050);
FORCEPROP 2 LAST CDS_LIB standard
J 0
(3850 -925);
DISPLAY INVISIBLE (3850 -925);
FORCEPROP 2 LAST PATH I3
J 0
(3425 -875);
DISPLAY 1.021277 (3425 -875);
DISPLAY INVISIBLE (3425 -875);
FORCEADD Q_RES..1
(6550 125);
FORCEPROP 1 LAST PART_NUMBER CS-3302FB01
J 0
(6450 175);
DISPLAY 0.617021 (6450 175);
PAINT BLUE (6450 175);
DISPLAY INVISIBLE (6450 175);
FORCEPROP 1 LAST WATTAGE 1/16W
J 2
(6675 200);
DISPLAY 0.617021 (6675 200);
PAINT SKYBLUE (6675 200);
FORCEPROP 1 LAST MATERIAL CHIP
J 0
(6450 225);
DISPLAY 0.617021 (6450 225);
PAINT SKYBLUE (6450 225);
FORCEPROP 1 LAST TOLERANCE 1%
J 0
(6700 125);
DISPLAY 0.617021 (6700 125);
PAINT SKYBLUE (6700 125);
FORCEPROP 1 LAST VALUE 3.3
J 2
(6675 125);
DISPLAY 0.617021 (6675 125);
PAINT SKYBLUE (6675 125);
FORCEPROP 1 LAST PACK_TYPE 0402LF
J 0
(6450 200);
DISPLAY 0.617021 (6450 200);
PAINT SKYBLUE (6450 200);
FORCEPROP 1 LAST LOCATION PR1790
J 0
(6350 125);
DISPLAY 0.617021 (6350 125);
PAINT AQUA (6350 125);
FORCEPROP 1 LASTPIN (6450 125) $PN 1
J 0
(6462 137);
DISPLAY 0.617021 (6462 137);
FORCEPROP 1 LASTPIN (6650 125) $PN 2
J 0
(6612 137);
DISPLAY 0.617021 (6612 137);
FORCEPROP 2 LAST CDS_LIB pure_quanta
J 0
(6550 125);
PAINT MONO (6550 125);
DISPLAY INVISIBLE (6550 125);
FORCEPROP 1 LAST PATH I30
J 0
(6500 275);
DISPLAY 0.978723 (6500 275);
PAINT WHITE (6500 275);
DISPLAY INVISIBLE (6500 275);
FORCEPROP 2 LAST $SEC 1
J 0
(6500 325);
DISPLAY 0.680851 (6500 325);
PAINT MONO (6500 325);
DISPLAY INVISIBLE (6500 325);
FORCEPROP 2 LAST CDS_SEC 1
J 0
(6500 325);
DISPLAY 1.021277 (6500 325);
DISPLAY INVISIBLE (6500 325);
FORCEADD Q_CAP..1
(6500 575);
FORCEPROP 1 LAST PART_NUMBER CH5103KEB01
J 0
(6550 425);
DISPLAY 0.617021 (6550 425);
PAINT BLUE (6550 425);
DISPLAY INVISIBLE (6550 425);
FORCEPROP 1 LAST TOLERANCE 10%
J 0
(6550 575);
DISPLAY 0.617021 (6550 575);
PAINT SKYBLUE (6550 575);
FORCEPROP 1 LAST VALUE 1UF
J 0
(6550 675);
DISPLAY 0.617021 (6550 675);
PAINT SKYBLUE (6550 675);
FORCEPROP 1 LAST VOLTAGE 16V
J 0
(6550 625);
DISPLAY 0.617021 (6550 625);
PAINT SKYBLUE (6550 625);
FORCEPROP 1 LAST PACK_TYPE C0402
J 0
(6550 475);
DISPLAY 0.617021 (6550 475);
PAINT SKYBLUE (6550 475);
FORCEPROP 1 LAST MATERIAL X6S
J 0
(6550 525);
DISPLAY 0.617021 (6550 525);
PAINT SKYBLUE (6550 525);
FORCEPROP 1 LAST LOCATION PC507_P1_6
J 0
(6550 725);
DISPLAY 0.617021 (6550 725);
PAINT AQUA (6550 725);
FORCEPROP 1 LASTPIN (6500 675) $PN 1
J 0
(6510 655);
DISPLAY 0.617021 (6510 655);
PAINT MONO (6510 655);
FORCEPROP 1 LASTPIN (6500 475) $PN 2
J 0
(6510 455);
DISPLAY 0.617021 (6510 455);
PAINT MONO (6510 455);
FORCEPROP 2 LAST CDS_LIB pure_quanta
J 0
(6500 575);
DISPLAY INVISIBLE (6500 575);
FORCEPROP 1 LAST PATH I31
J 0
(6550 725);
DISPLAY 0.978723 (6550 725);
PAINT WHITE (6550 725);
DISPLAY INVISIBLE (6550 725);
FORCEPROP 1 LAST LOCATION PC507_P1_6
J 0
(6550 775);
DISPLAY 1.021277 (6550 775);
PAINT AQUA (6550 775);
DISPLAY INVISIBLE (6550 775);
FORCEPROP 0 LAST $SEC 1
J 0
(6550 775);
DISPLAY 0.680851 (6550 775);
PAINT MONO (6550 775);
DISPLAY INVISIBLE (6550 775);
FORCEPROP 0 LAST CDS_SEC 1
J 0
(6550 775);
DISPLAY 1.021277 (6550 775);
DISPLAY INVISIBLE (6550 775);
FORCEADD UNIVERSAL_GND..1
(5975 1775);
FORCEPROP 3 LASTPIN (5975 1825) SIG_NAME GND\g
J 0
(5985 1835);
DISPLAY 0.659574 (5985 1835);
PAINT MONO (5985 1835);
DISPLAY INVISIBLE (5985 1835);
FORCEPROP 2 LAST CDS_LIB logical_power
J 0
(5975 1775);
PAINT MONO (5975 1775);
DISPLAY INVISIBLE (5975 1775);
FORCEPROP 1 LAST HDL_POWER GND
J 1
(6000 1700);
DISPLAY 0.872340 (6000 1700);
PAINT GREEN (6000 1700);
DISPLAY INVISIBLE (6000 1700);
FORCEPROP 1 LAST PATH I32
J 0
(6050 1775);
DISPLAY 0.872340 (6050 1775);
PAINT AQUA (6050 1775);
DISPLAY INVISIBLE (6050 1775);
FORCEADD Q_CAP..1
(6900 575);
FORCEPROP 1 LAST PART_NUMBER CH6223MEA01
J 0
(6950 425);
DISPLAY 0.617021 (6950 425);
PAINT BLUE (6950 425);
DISPLAY INVISIBLE (6950 425);
FORCEPROP 1 LAST MATERIAL X6S
J 0
(6950 525);
DISPLAY 0.617021 (6950 525);
PAINT SKYBLUE (6950 525);
FORCEPROP 1 LAST TOLERANCE 20%
J 0
(6950 575);
DISPLAY 0.617021 (6950 575);
PAINT SKYBLUE (6950 575);
FORCEPROP 1 LAST VALUE 22UF
J 0
(6950 675);
DISPLAY 0.617021 (6950 675);
PAINT SKYBLUE (6950 675);
FORCEPROP 1 LAST VOLTAGE 16V
J 0
(6950 625);
DISPLAY 0.617021 (6950 625);
PAINT SKYBLUE (6950 625);
FORCEPROP 1 LAST PACK_TYPE C0805
J 0
(6950 475);
DISPLAY 0.617021 (6950 475);
PAINT SKYBLUE (6950 475);
FORCEPROP 1 LAST LOCATION PC511_P1_6
J 0
(6950 725);
DISPLAY 0.617021 (6950 725);
PAINT AQUA (6950 725);
FORCEPROP 1 LASTPIN (6900 675) $PN 1
J 0
(6910 655);
DISPLAY 0.617021 (6910 655);
PAINT MONO (6910 655);
FORCEPROP 1 LASTPIN (6900 475) $PN 2
J 0
(6910 455);
DISPLAY 0.617021 (6910 455);
PAINT MONO (6910 455);
FORCEPROP 2 LAST CDS_LIB pure_quanta
J 0
(6900 575);
DISPLAY INVISIBLE (6900 575);
FORCEPROP 1 LAST PATH I33
J 0
(6950 725);
DISPLAY 0.978723 (6950 725);
PAINT WHITE (6950 725);
DISPLAY INVISIBLE (6950 725);
FORCEPROP 1 LAST LOCATION PC511_P1_6
J 0
(6950 775);
DISPLAY 1.021277 (6950 775);
PAINT AQUA (6950 775);
DISPLAY INVISIBLE (6950 775);
FORCEPROP 0 LAST $SEC 1
J 0
(6950 775);
DISPLAY 0.680851 (6950 775);
PAINT MONO (6950 775);
DISPLAY INVISIBLE (6950 775);
FORCEPROP 0 LAST CDS_SEC 1
J 0
(6950 775);
DISPLAY 1.021277 (6950 775);
DISPLAY INVISIBLE (6950 775);
FORCEADD Q_CAP..1
(7300 575);
FORCEPROP 1 LAST PART_NUMBER CH6223MEA01
J 0
(7350 425);
DISPLAY 0.617021 (7350 425);
PAINT BLUE (7350 425);
DISPLAY INVISIBLE (7350 425);
FORCEPROP 1 LAST MATERIAL X6S
J 0
(7350 525);
DISPLAY 0.617021 (7350 525);
PAINT SKYBLUE (7350 525);
FORCEPROP 1 LAST TOLERANCE 20%
J 0
(7350 575);
DISPLAY 0.617021 (7350 575);
PAINT SKYBLUE (7350 575);
FORCEPROP 1 LAST VALUE 22UF
J 0
(7350 675);
DISPLAY 0.617021 (7350 675);
PAINT SKYBLUE (7350 675);
FORCEPROP 1 LAST VOLTAGE 16V
J 0
(7350 625);
DISPLAY 0.617021 (7350 625);
PAINT SKYBLUE (7350 625);
FORCEPROP 1 LAST PACK_TYPE C0805
J 0
(7350 475);
DISPLAY 0.617021 (7350 475);
PAINT SKYBLUE (7350 475);
FORCEPROP 1 LAST LOCATION PC513_P1_6
J 0
(7350 725);
DISPLAY 0.617021 (7350 725);
PAINT AQUA (7350 725);
FORCEPROP 1 LASTPIN (7300 675) $PN 1
J 0
(7310 655);
DISPLAY 0.617021 (7310 655);
PAINT MONO (7310 655);
FORCEPROP 1 LASTPIN (7300 475) $PN 2
J 0
(7310 455);
DISPLAY 0.617021 (7310 455);
PAINT MONO (7310 455);
FORCEPROP 2 LAST CDS_LIB pure_quanta
J 0
(7300 575);
DISPLAY INVISIBLE (7300 575);
FORCEPROP 1 LAST PATH I34
J 0
(7350 725);
DISPLAY 0.978723 (7350 725);
PAINT WHITE (7350 725);
DISPLAY INVISIBLE (7350 725);
FORCEPROP 1 LAST LOCATION PC513_P1_6
J 0
(7350 775);
DISPLAY 1.021277 (7350 775);
PAINT AQUA (7350 775);
DISPLAY INVISIBLE (7350 775);
FORCEPROP 0 LAST $SEC 1
J 0
(7350 775);
DISPLAY 0.680851 (7350 775);
PAINT MONO (7350 775);
DISPLAY INVISIBLE (7350 775);
FORCEPROP 0 LAST CDS_SEC 1
J 0
(7350 775);
DISPLAY 1.021277 (7350 775);
DISPLAY INVISIBLE (7350 775);
FORCEADD Q_CAP..1
(7675 575);
FORCEPROP 1 LAST PART_NUMBER CH6223MEA01
J 0
(7725 425);
DISPLAY 0.617021 (7725 425);
PAINT BLUE (7725 425);
DISPLAY INVISIBLE (7725 425);
FORCEPROP 1 LAST MATERIAL X6S
J 0
(7725 525);
DISPLAY 0.617021 (7725 525);
PAINT SKYBLUE (7725 525);
FORCEPROP 1 LAST TOLERANCE 20%
J 0
(7725 575);
DISPLAY 0.617021 (7725 575);
PAINT SKYBLUE (7725 575);
FORCEPROP 1 LAST VALUE 22UF
J 0
(7725 675);
DISPLAY 0.617021 (7725 675);
PAINT SKYBLUE (7725 675);
FORCEPROP 1 LAST VOLTAGE 16V
J 0
(7725 625);
DISPLAY 0.617021 (7725 625);
PAINT SKYBLUE (7725 625);
FORCEPROP 1 LAST PACK_TYPE C0805
J 0
(7725 475);
DISPLAY 0.617021 (7725 475);
PAINT SKYBLUE (7725 475);
FORCEPROP 1 LAST LOCATION PC515_P1_6
J 0
(7725 725);
DISPLAY 0.617021 (7725 725);
PAINT AQUA (7725 725);
FORCEPROP 1 LASTPIN (7675 675) $PN 1
J 0
(7685 655);
DISPLAY 0.617021 (7685 655);
PAINT MONO (7685 655);
FORCEPROP 1 LASTPIN (7675 475) $PN 2
J 0
(7685 455);
DISPLAY 0.617021 (7685 455);
PAINT MONO (7685 455);
FORCEPROP 2 LAST CDS_LIB pure_quanta
J 0
(7675 575);
DISPLAY INVISIBLE (7675 575);
FORCEPROP 1 LAST PATH I35
J 0
(7725 725);
DISPLAY 0.978723 (7725 725);
PAINT WHITE (7725 725);
DISPLAY INVISIBLE (7725 725);
FORCEPROP 1 LAST LOCATION PC515_P1_6
J 0
(7725 775);
DISPLAY 1.021277 (7725 775);
PAINT AQUA (7725 775);
DISPLAY INVISIBLE (7725 775);
FORCEPROP 0 LAST $SEC 1
J 0
(7725 775);
DISPLAY 0.680851 (7725 775);
PAINT MONO (7725 775);
DISPLAY INVISIBLE (7725 775);
FORCEPROP 0 LAST CDS_SEC 1
J 0
(7725 775);
DISPLAY 1.021277 (7725 775);
DISPLAY INVISIBLE (7725 775);
FORCEADD Q_CAP..2
(4125 2300);
FORCEPROP 1 LAST PART_NUMBER CH4104K1B00
J 1
(4350 2325);
DISPLAY 0.617021 (4350 2325);
PAINT BLUE (4350 2325);
DISPLAY INVISIBLE (4350 2325);
FORCEPROP 1 LAST MATERIAL X7R
J 0
(4500 2325);
DISPLAY 0.617021 (4500 2325);
PAINT SKYBLUE (4500 2325);
FORCEPROP 1 LAST TOLERANCE 10%
J 2
(4650 2325);
DISPLAY 0.617021 (4650 2325);
PAINT SKYBLUE (4650 2325);
FORCEPROP 1 LAST VALUE 0.1UF
J 2
(4350 2300);
DISPLAY 0.617021 (4350 2300);
PAINT SKYBLUE (4350 2300);
FORCEPROP 1 LAST VOLTAGE 25V
J 0
(4375 2300);
DISPLAY 0.617021 (4375 2300);
PAINT SKYBLUE (4375 2300);
FORCEPROP 1 LAST PACK_TYPE 0402
J 1
(4500 2300);
DISPLAY 0.617021 (4500 2300);
PAINT SKYBLUE (4500 2300);
FORCEPROP 1 LAST LOCATION PC1361
J 1
(3925 2300);
DISPLAY 0.617021 (3925 2300);
PAINT AQUA (3925 2300);
FORCEPROP 1 LASTPIN (4025 2300) $PN 1
J 0
(4015 2315);
DISPLAY 0.617021 (4015 2315);
FORCEPROP 1 LASTPIN (4225 2300) $PN 2
J 0
(4210 2315);
DISPLAY 0.617021 (4210 2315);
FORCEPROP 2 LAST CDS_LIB pure_quanta
J 0
(4125 2300);
PAINT MONO (4125 2300);
DISPLAY INVISIBLE (4125 2300);
FORCEPROP 1 LAST PATH I36
J 0
(4125 2500);
DISPLAY 0.978723 (4125 2500);
PAINT WHITE (4125 2500);
DISPLAY INVISIBLE (4125 2500);
FORCEPROP 2 LAST $SEC 1
J 0
(4125 2550);
DISPLAY 0.680851 (4125 2550);
PAINT MONO (4125 2550);
DISPLAY INVISIBLE (4125 2550);
FORCEPROP 2 LAST CDS_SEC 1
J 0
(4125 2550);
DISPLAY 1.021277 (4125 2550);
DISPLAY INVISIBLE (4125 2550);
FORCEADD Q_CAP..1
(3800 3000);
FORCEPROP 1 LAST PART_NUMBER CH5222KEB01
J 0
(3850 2825);
DISPLAY 0.617021 (3850 2825);
PAINT BLUE (3850 2825);
DISPLAY INVISIBLE (3850 2825);
FORCEPROP 1 LAST MATERIAL X6S
J 0
(3850 2925);
DISPLAY 0.617021 (3850 2925);
PAINT SKYBLUE (3850 2925);
FORCEPROP 1 LAST TOLERANCE 10%
J 0
(3850 2975);
DISPLAY 0.617021 (3850 2975);
PAINT SKYBLUE (3850 2975);
FORCEPROP 1 LAST VALUE 2.2UF
J 0
(3850 3075);
DISPLAY 0.617021 (3850 3075);
PAINT SKYBLUE (3850 3075);
FORCEPROP 1 LAST VOLTAGE 10V
J 0
(3850 3025);
DISPLAY 0.617021 (3850 3025);
PAINT SKYBLUE (3850 3025);
FORCEPROP 1 LAST PACK_TYPE C0402
J 0
(3850 2875);
DISPLAY 0.617021 (3850 2875);
PAINT SKYBLUE (3850 2875);
FORCEPROP 1 LAST LOCATION PC502
J 0
(3850 3125);
DISPLAY 0.617021 (3850 3125);
PAINT AQUA (3850 3125);
FORCEPROP 1 LASTPIN (3800 3100) $PN 1
J 0
(3810 3080);
DISPLAY 0.617021 (3810 3080);
PAINT MONO (3810 3080);
FORCEPROP 1 LASTPIN (3800 2900) $PN 2
J 0
(3810 2880);
DISPLAY 0.617021 (3810 2880);
PAINT MONO (3810 2880);
FORCEPROP 2 LAST CDS_LIB pure_quanta
J 0
(3800 3000);
DISPLAY INVISIBLE (3800 3000);
FORCEPROP 1 LAST PATH I37
J 0
(3850 3150);
DISPLAY 0.978723 (3850 3150);
PAINT WHITE (3850 3150);
DISPLAY INVISIBLE (3850 3150);
FORCEPROP 1 LAST LOCATION PC502
J 0
(3850 3175);
DISPLAY 1.021277 (3850 3175);
PAINT AQUA (3850 3175);
DISPLAY INVISIBLE (3850 3175);
FORCEPROP 0 LAST $SEC 1
J 0
(3850 3175);
DISPLAY 0.680851 (3850 3175);
PAINT MONO (3850 3175);
DISPLAY INVISIBLE (3850 3175);
FORCEPROP 0 LAST CDS_SEC 1
J 0
(3850 3175);
DISPLAY 1.021277 (3850 3175);
DISPLAY INVISIBLE (3850 3175);
FORCEADD UNIVERSAL_GND..1
(3800 2750);
FORCEPROP 3 LASTPIN (3800 2800) SIG_NAME GND\g
J 0
(3810 2810);
DISPLAY 0.659574 (3810 2810);
PAINT MONO (3810 2810);
DISPLAY INVISIBLE (3810 2810);
FORCEPROP 2 LAST CDS_LIB logical_power
J 0
(3800 2750);
PAINT MONO (3800 2750);
DISPLAY INVISIBLE (3800 2750);
FORCEPROP 1 LAST HDL_POWER GND
J 1
(3825 2675);
DISPLAY 0.872340 (3825 2675);
PAINT GREEN (3825 2675);
DISPLAY INVISIBLE (3825 2675);
FORCEPROP 1 LAST PATH I38
J 0
(3875 2750);
DISPLAY 0.872340 (3875 2750);
PAINT AQUA (3875 2750);
DISPLAY INVISIBLE (3875 2750);
FORCEADD Q_RES..2
(3800 3500);
FORCEPROP 1 LAST PART_NUMBER CS-2202FB01
J 0
(3840 3375);
DISPLAY 0.617021 (3840 3375);
PAINT BLUE (3840 3375);
DISPLAY INVISIBLE (3840 3375);
FORCEPROP 1 LAST WATTAGE 1/16W
J 0
(3840 3475);
DISPLAY 0.617021 (3840 3475);
PAINT SKYBLUE (3840 3475);
FORCEPROP 1 LAST MATERIAL CHIP
J 0
(3840 3425);
DISPLAY 0.617021 (3840 3425);
PAINT SKYBLUE (3840 3425);
FORCEPROP 1 LAST TOLERANCE 1%
J 0
(3845 3525);
DISPLAY 0.617021 (3845 3525);
PAINT SKYBLUE (3845 3525);
FORCEPROP 1 LAST VALUE 2.2
J 0
(3845 3575);
DISPLAY 0.617021 (3845 3575);
PAINT SKYBLUE (3845 3575);
FORCEPROP 1 LAST PACK_TYPE 0402LF
J 0
(3840 3325);
DISPLAY 0.617021 (3840 3325);
PAINT SKYBLUE (3840 3325);
FORCEPROP 1 LAST LOCATION PR294
J 0
(3845 3625);
DISPLAY 0.617021 (3845 3625);
PAINT AQUA (3845 3625);
FORCEPROP 1 LASTPIN (3800 3600) $PN 1
J 0
(3805 3562);
DISPLAY 0.617021 (3805 3562);
PAINT MONO (3805 3562);
FORCEPROP 1 LASTPIN (3800 3400) $PN 2
J 0
(3805 3410);
DISPLAY 0.617021 (3805 3410);
PAINT MONO (3805 3410);
FORCEPROP 2 LAST CDS_LIB pure_quanta
J 0
(3800 3500);
DISPLAY INVISIBLE (3800 3500);
FORCEPROP 1 LAST PATH I39
J 0
(3850 3675);
DISPLAY 0.978723 (3850 3675);
PAINT WHITE (3850 3675);
DISPLAY INVISIBLE (3850 3675);
FORCEPROP 1 LAST LOCATION PR294
J 0
(3850 3675);
DISPLAY 1.021277 (3850 3675);
PAINT AQUA (3850 3675);
DISPLAY INVISIBLE (3850 3675);
FORCEPROP 0 LAST $SEC 1
J 0
(3850 3675);
DISPLAY 0.680851 (3850 3675);
PAINT MONO (3850 3675);
DISPLAY INVISIBLE (3850 3675);
FORCEPROP 0 LAST CDS_SEC 1
J 0
(3850 3675);
DISPLAY 1.021277 (3850 3675);
DISPLAY INVISIBLE (3850 3675);
FORCEADD UNIVERSAL_GND..1
(3275 -600);
FORCEPROP 3 LASTPIN (3275 -550) SIG_NAME GND\g
J 0
(3285 -540);
DISPLAY 0.659574 (3285 -540);
PAINT MONO (3285 -540);
DISPLAY INVISIBLE (3285 -540);
FORCEPROP 2 LAST CDS_LIB logical_power
J 0
(3275 -600);
PAINT MONO (3275 -600);
DISPLAY INVISIBLE (3275 -600);
FORCEPROP 1 LAST HDL_POWER GND
J 1
(3300 -675);
DISPLAY 0.872340 (3300 -675);
PAINT GREEN (3300 -675);
DISPLAY INVISIBLE (3300 -675);
FORCEPROP 1 LAST PATH I4
J 0
(3350 -600);
DISPLAY 0.872340 (3350 -600);
PAINT AQUA (3350 -600);
DISPLAY INVISIBLE (3350 -600);
FORCEADD UNIVERSAL_GND..1
(4225 3275);
FORCEPROP 3 LASTPIN (4225 3325) SIG_NAME GND\g
J 0
(4235 3335);
DISPLAY 0.659574 (4235 3335);
PAINT MONO (4235 3335);
DISPLAY INVISIBLE (4235 3335);
FORCEPROP 2 LAST CDS_LIB logical_power
J 0
(4225 3275);
PAINT MONO (4225 3275);
DISPLAY INVISIBLE (4225 3275);
FORCEPROP 1 LAST HDL_POWER GND
J 1
(4250 3200);
DISPLAY 0.872340 (4250 3200);
PAINT GREEN (4250 3200);
DISPLAY INVISIBLE (4250 3200);
FORCEPROP 1 LAST PATH I40
J 0
(4300 3275);
DISPLAY 0.872340 (4300 3275);
PAINT AQUA (4300 3275);
DISPLAY INVISIBLE (4300 3275);
FORCEADD Q_CAP..1
(4225 3500);
FORCEPROP 1 LAST PART_NUMBER CH5222KEB01
J 0
(4275 3375);
DISPLAY 0.617021 (4275 3375);
PAINT BLUE (4275 3375);
DISPLAY INVISIBLE (4275 3375);
FORCEPROP 1 LAST MATERIAL X6S
J 0
(4275 3425);
DISPLAY 0.617021 (4275 3425);
PAINT SKYBLUE (4275 3425);
FORCEPROP 1 LAST TOLERANCE 10%
J 0
(4275 3475);
DISPLAY 0.617021 (4275 3475);
PAINT SKYBLUE (4275 3475);
FORCEPROP 1 LAST VALUE 2.2UF
J 0
(4275 3575);
DISPLAY 0.617021 (4275 3575);
PAINT SKYBLUE (4275 3575);
FORCEPROP 1 LAST VOLTAGE 10V
J 0
(4275 3525);
DISPLAY 0.617021 (4275 3525);
PAINT SKYBLUE (4275 3525);
FORCEPROP 1 LAST PACK_TYPE C0402
J 0
(4275 3325);
DISPLAY 0.617021 (4275 3325);
PAINT SKYBLUE (4275 3325);
FORCEPROP 1 LAST LOCATION PC504_P1_5
J 0
(4275 3625);
DISPLAY 0.617021 (4275 3625);
PAINT AQUA (4275 3625);
FORCEPROP 1 LASTPIN (4225 3600) $PN 1
J 0
(4235 3580);
DISPLAY 0.617021 (4235 3580);
PAINT MONO (4235 3580);
FORCEPROP 1 LASTPIN (4225 3400) $PN 2
J 0
(4235 3380);
DISPLAY 0.617021 (4235 3380);
PAINT MONO (4235 3380);
FORCEPROP 2 LAST CDS_LIB pure_quanta
J 0
(4225 3500);
DISPLAY INVISIBLE (4225 3500);
FORCEPROP 1 LAST PATH I41
J 0
(4275 3650);
DISPLAY 0.978723 (4275 3650);
PAINT WHITE (4275 3650);
DISPLAY INVISIBLE (4275 3650);
FORCEPROP 1 LAST LOCATION PC504_P1_5
J 0
(4275 3675);
DISPLAY 1.021277 (4275 3675);
PAINT AQUA (4275 3675);
DISPLAY INVISIBLE (4275 3675);
FORCEPROP 0 LAST $SEC 1
J 0
(4275 3675);
DISPLAY 0.680851 (4275 3675);
PAINT MONO (4275 3675);
DISPLAY INVISIBLE (4275 3675);
FORCEPROP 0 LAST CDS_SEC 1
J 0
(4275 3675);
DISPLAY 1.021277 (4275 3675);
DISPLAY INVISIBLE (4275 3675);
FORCEADD VCC15..1
(3800 3825);
FORCEPROP 3 LASTPIN (3800 3775) SIG_NAME PVCCIN_CPU1_PVCC\g
J 0
(3810 3785);
DISPLAY 0.659574 (3810 3785);
PAINT MONO (3810 3785);
DISPLAY INVISIBLE (3810 3785);
FORCEPROP 1 LAST HDL_POWER PVCCIN_CPU1_PVCC
J 1
(3800 3875);
DISPLAY 0.617021 (3800 3875);
PAINT GREEN (3800 3875);
FORCEPROP 2 LAST CDS_LIB logical_power
J 0
(3800 3825);
DISPLAY INVISIBLE (3800 3825);
FORCEPROP 1 LAST PATH I42
J 0
(3850 3850);
DISPLAY 0.872340 (3850 3850);
PAINT AQUA (3850 3850);
DISPLAY INVISIBLE (3850 3850);
FORCEADD OFFPAGE..6
(6800 2250);
FORCEPROP 2 LAST $XR0 288 
J 0
(6490 2250);
DISPLAY 0.638298 (6490 2250);
PAINT MONO (6490 2250);
FORCEPROP 1 LAST COMMENT_BODY TRUE
J 0
(6900 2175);
DISPLAY 0.872340 (6900 2175);
PAINT GREEN (6900 2175);
DISPLAY INVISIBLE (6900 2175);
FORCEPROP 1 LAST OFFPAGE TRUE
J 0
(7125 2125);
DISPLAY 0.872340 (7125 2125);
DISPLAY INVISIBLE (7125 2125);
FORCEPROP 2 LAST CDS_LIB standard
J 0
(6800 2250);
DISPLAY INVISIBLE (6800 2250);
FORCEPROP 2 LAST PATH I43
J 0
(6500 2300);
DISPLAY 1.021277 (6500 2300);
DISPLAY INVISIBLE (6500 2300);
FORCEADD Q_RES..1
(6575 2950);
FORCEPROP 1 LAST PART_NUMBER CS-3302FB01
J 0
(6475 3000);
DISPLAY 0.617021 (6475 3000);
PAINT BLUE (6475 3000);
DISPLAY INVISIBLE (6475 3000);
FORCEPROP 1 LAST WATTAGE 1/16W
J 2
(6700 3025);
DISPLAY 0.617021 (6700 3025);
PAINT SKYBLUE (6700 3025);
FORCEPROP 1 LAST MATERIAL CHIP
J 0
(6475 3050);
DISPLAY 0.617021 (6475 3050);
PAINT SKYBLUE (6475 3050);
FORCEPROP 1 LAST TOLERANCE 1%
J 0
(6725 2950);
DISPLAY 0.617021 (6725 2950);
PAINT SKYBLUE (6725 2950);
FORCEPROP 1 LAST VALUE 3.3
J 2
(6700 2950);
DISPLAY 0.617021 (6700 2950);
PAINT SKYBLUE (6700 2950);
FORCEPROP 1 LAST PACK_TYPE 0402LF
J 0
(6475 3025);
DISPLAY 0.617021 (6475 3025);
PAINT SKYBLUE (6475 3025);
FORCEPROP 1 LAST LOCATION PR1791
J 0
(6375 2950);
DISPLAY 0.617021 (6375 2950);
PAINT AQUA (6375 2950);
FORCEPROP 1 LASTPIN (6475 2950) $PN 1
J 0
(6487 2962);
DISPLAY 0.617021 (6487 2962);
FORCEPROP 1 LASTPIN (6675 2950) $PN 2
J 0
(6637 2962);
DISPLAY 0.617021 (6637 2962);
FORCEPROP 2 LAST CDS_LIB pure_quanta
J 0
(6575 2950);
PAINT MONO (6575 2950);
DISPLAY INVISIBLE (6575 2950);
FORCEPROP 1 LAST PATH I44
J 0
(6525 3100);
DISPLAY 0.978723 (6525 3100);
PAINT WHITE (6525 3100);
DISPLAY INVISIBLE (6525 3100);
FORCEPROP 2 LAST $SEC 1
J 0
(6525 3150);
DISPLAY 0.680851 (6525 3150);
PAINT MONO (6525 3150);
DISPLAY INVISIBLE (6525 3150);
FORCEPROP 2 LAST CDS_SEC 1
J 0
(6525 3150);
DISPLAY 1.021277 (6525 3150);
DISPLAY INVISIBLE (6525 3150);
FORCEADD Q_CAP..1
(6125 3400);
FORCEPROP 1 LAST PART_NUMBER TMP_QCH2336K1B12
J 0
(6175 3250);
DISPLAY 0.617021 (6175 3250);
PAINT BLUE (6175 3250);
DISPLAY INVISIBLE (6175 3250);
FORCEPROP 1 LAST MATERIAL X7R
J 0
(6175 3350);
DISPLAY 0.617021 (6175 3350);
PAINT SKYBLUE (6175 3350);
FORCEPROP 1 LAST TOLERANCE 10%
J 0
(6175 3400);
DISPLAY 0.617021 (6175 3400);
PAINT SKYBLUE (6175 3400);
FORCEPROP 1 LAST VALUE 3300PF
J 0
(6175 3500);
DISPLAY 0.617021 (6175 3500);
PAINT SKYBLUE (6175 3500);
FORCEPROP 1 LAST VOLTAGE 50V
J 0
(6175 3450);
DISPLAY 0.617021 (6175 3450);
PAINT SKYBLUE (6175 3450);
FORCEPROP 1 LAST PACK_TYPE 0402
J 0
(6175 3300);
DISPLAY 0.617021 (6175 3300);
PAINT SKYBLUE (6175 3300);
FORCEPROP 1 LAST LOCATION PC506_P1_5
J 0
(6175 3550);
DISPLAY 0.617021 (6175 3550);
PAINT AQUA (6175 3550);
FORCEPROP 1 LASTPIN (6125 3500) $PN 1
J 0
(6135 3480);
DISPLAY 0.617021 (6135 3480);
PAINT MONO (6135 3480);
FORCEPROP 1 LASTPIN (6125 3300) $PN 2
J 0
(6135 3280);
DISPLAY 0.617021 (6135 3280);
PAINT MONO (6135 3280);
FORCEPROP 2 LAST CDS_LIB pure_quanta
J 0
(6125 3400);
DISPLAY INVISIBLE (6125 3400);
FORCEPROP 1 LAST PATH I45
J 0
(6175 3550);
DISPLAY 0.978723 (6175 3550);
PAINT WHITE (6175 3550);
DISPLAY INVISIBLE (6175 3550);
FORCEPROP 1 LAST LOCATION PC506_P1_5
J 0
(6175 3600);
DISPLAY 1.021277 (6175 3600);
PAINT AQUA (6175 3600);
DISPLAY INVISIBLE (6175 3600);
FORCEPROP 0 LAST $SEC 1
J 0
(6175 3600);
DISPLAY 0.680851 (6175 3600);
PAINT MONO (6175 3600);
DISPLAY INVISIBLE (6175 3600);
FORCEPROP 0 LAST CDS_SEC 1
J 0
(6175 3600);
DISPLAY 1.021277 (6175 3600);
DISPLAY INVISIBLE (6175 3600);
FORCEADD Q_CAP..1
(6525 3400);
FORCEPROP 1 LAST PART_NUMBER CH5103KEB01
J 0
(6575 3250);
DISPLAY 0.617021 (6575 3250);
PAINT BLUE (6575 3250);
DISPLAY INVISIBLE (6575 3250);
FORCEPROP 1 LAST MATERIAL X6S
J 0
(6575 3350);
DISPLAY 0.617021 (6575 3350);
PAINT SKYBLUE (6575 3350);
FORCEPROP 1 LAST TOLERANCE 10%
J 0
(6575 3400);
DISPLAY 0.617021 (6575 3400);
PAINT SKYBLUE (6575 3400);
FORCEPROP 1 LAST VALUE 1UF
J 0
(6575 3500);
DISPLAY 0.617021 (6575 3500);
PAINT SKYBLUE (6575 3500);
FORCEPROP 1 LAST VOLTAGE 16V
J 0
(6575 3450);
DISPLAY 0.617021 (6575 3450);
PAINT SKYBLUE (6575 3450);
FORCEPROP 1 LAST PACK_TYPE C0402
J 0
(6575 3300);
DISPLAY 0.617021 (6575 3300);
PAINT SKYBLUE (6575 3300);
FORCEPROP 1 LAST LOCATION PC508_P1_5
J 0
(6575 3550);
DISPLAY 0.617021 (6575 3550);
PAINT AQUA (6575 3550);
FORCEPROP 1 LASTPIN (6525 3500) $PN 1
J 0
(6535 3480);
DISPLAY 0.617021 (6535 3480);
PAINT MONO (6535 3480);
FORCEPROP 1 LASTPIN (6525 3300) $PN 2
J 0
(6535 3280);
DISPLAY 0.617021 (6535 3280);
PAINT MONO (6535 3280);
FORCEPROP 2 LAST CDS_LIB pure_quanta
J 0
(6525 3400);
DISPLAY INVISIBLE (6525 3400);
FORCEPROP 1 LAST PATH I46
J 0
(6575 3550);
DISPLAY 0.978723 (6575 3550);
PAINT WHITE (6575 3550);
DISPLAY INVISIBLE (6575 3550);
FORCEPROP 1 LAST LOCATION PC508_P1_5
J 0
(6575 3600);
DISPLAY 1.021277 (6575 3600);
PAINT AQUA (6575 3600);
DISPLAY INVISIBLE (6575 3600);
FORCEPROP 0 LAST $SEC 1
J 0
(6575 3600);
DISPLAY 0.680851 (6575 3600);
PAINT MONO (6575 3600);
DISPLAY INVISIBLE (6575 3600);
FORCEPROP 0 LAST CDS_SEC 1
J 0
(6575 3600);
DISPLAY 1.021277 (6575 3600);
DISPLAY INVISIBLE (6575 3600);
FORCEADD Q_CAP..1
R 2
(7300 2775);
FORCEPROP 1 LAST PART_NUMBER CH4106K1B01
J 2
(7250 2700);
DISPLAY 0.617021 (7250 2700);
PAINT BLUE (7250 2700);
DISPLAY INVISIBLE (7250 2700);
FORCEPROP 1 LAST MATERIAL X7R
J 2
(7250 2725);
DISPLAY 0.617021 (7250 2725);
PAINT SKYBLUE (7250 2725);
FORCEPROP 1 LAST TOLERANCE 10%
J 2
(7250 2750);
DISPLAY 0.617021 (7250 2750);
PAINT SKYBLUE (7250 2750);
FORCEPROP 1 LAST PACK_TYPE C0402
J 2
(7250 2675);
DISPLAY 0.617021 (7250 2675);
PAINT SKYBLUE (7250 2675);
FORCEPROP 1 LAST VALUE 100NF
J 2
(7250 2800);
DISPLAY 0.617021 (7250 2800);
PAINT SKYBLUE (7250 2800);
FORCEPROP 1 LAST VOLTAGE 50V
J 2
(7250 2775);
DISPLAY 0.617021 (7250 2775);
PAINT SKYBLUE (7250 2775);
FORCEPROP 1 LAST LOCATION PC510
J 2
(7250 2850);
DISPLAY 0.617021 (7250 2850);
PAINT AQUA (7250 2850);
FORCEPROP 1 LASTPIN (7300 2875) $PN 1
J 2
(7290 2855);
DISPLAY 0.617021 (7290 2855);
FORCEPROP 1 LASTPIN (7300 2675) $PN 2
J 2
(7290 2655);
DISPLAY 0.617021 (7290 2655);
FORCEPROP 2 LAST CDS_LIB pure_quanta
J 2
(7300 2775);
PAINT MONO (7300 2775);
DISPLAY INVISIBLE (7300 2775);
FORCEPROP 1 LAST PATH I47
J 2
(7250 2925);
DISPLAY 0.978723 (7250 2925);
PAINT WHITE (7250 2925);
DISPLAY INVISIBLE (7250 2925);
FORCEPROP 2 LAST $SEC 1
J 0
(7250 2975);
DISPLAY 0.680851 (7250 2975);
PAINT MONO (7250 2975);
DISPLAY INVISIBLE (7250 2975);
FORCEPROP 2 LAST CDS_SEC 1
J 0
(7250 2975);
DISPLAY 1.021277 (7250 2975);
DISPLAY INVISIBLE (7250 2975);
FORCEADD Q_INDUCTOR4P_14..1
(7775 2375);
FORCEPROP 1 LAST PART_NUMBER CV+15^0TZ04
J 0
(7550 2535);
DISPLAY 0.617021 (7550 2535);
PAINT BLUE (7550 2535);
DISPLAY INVISIBLE (7550 2535);
FORCEPROP 1 LAST MATERIAL IND
J 0
(7550 2585);
DISPLAY 0.617021 (7550 2585);
PAINT SKYBLUE (7550 2585);
FORCEPROP 2 LAST VALUE 150NH
J 0
(7550 2675);
DISPLAY 0.617021 (7550 2675);
PAINT SKYBLUE (7550 2675);
FORCEPROP 2 LAST PART_TYPE SMLF
J 0
(7550 2725);
DISPLAY 1.021277 (7550 2725);
FORCEPROP 1 LAST LOCATION PL27
J 0
(7550 2630);
DISPLAY 0.617021 (7550 2630);
PAINT AQUA (7550 2630);
FORCEPROP 2 LASTPIN (7375 2500) $PN 1
J 2
(7365 2510);
DISPLAY 0.617021 (7365 2510);
PAINT MONO (7365 2510);
FORCEPROP 2 LASTPIN (7375 2250) $PN 2
J 2
(7365 2260);
DISPLAY 0.617021 (7365 2260);
PAINT MONO (7365 2260);
FORCEPROP 2 LASTPIN (8175 2250) $PN 3
J 0
(8185 2260);
DISPLAY 0.617021 (8185 2260);
PAINT MONO (8185 2260);
FORCEPROP 2 LASTPIN (8175 2500) $PN 4
J 0
(8185 2510);
DISPLAY 0.617021 (8185 2510);
PAINT MONO (8185 2510);
FORCEPROP 1 LAST NEEDS_NO_SIZE TRUE
J 0
(7775 2375);
DISPLAY 0.468085 (7775 2375);
PAINT GREEN (7775 2375);
DISPLAY INVISIBLE (7775 2375);
FORCEPROP 2 LAST CDS_LIB pure_quanta
J 0
(7775 2375);
DISPLAY INVISIBLE (7775 2375);
FORCEPROP 2 LAST SEC_TYPE 
J 0
(7550 2775);
DISPLAY 1.021277 (7550 2775);
DISPLAY INVISIBLE (7550 2775);
FORCEPROP 1 LAST PATH I48
J 0
(7975 2530);
DISPLAY 0.723404 (7975 2530);
PAINT GREEN (7975 2530);
DISPLAY INVISIBLE (7975 2530);
FORCEPROP 2 LAST SEC 1
J 0
(7550 2775);
DISPLAY 0.680851 (7550 2775);
PAINT MONO (7550 2775);
DISPLAY INVISIBLE (7550 2775);
FORCEADD Q_RES..1
(7900 1975);
FORCEPROP 1 LAST PART_NUMBER CS00002JB13
J 0
(7775 2025);
DISPLAY 0.617021 (7775 2025);
PAINT BLUE (7775 2025);
DISPLAY INVISIBLE (7775 2025);
FORCEPROP 1 LAST MATERIAL CHIP
J 0
(8175 1975);
DISPLAY 0.617021 (8175 1975);
PAINT SKYBLUE (8175 1975);
FORCEPROP 1 LAST TOLERANCE 5%
J 0
(8100 1975);
DISPLAY 0.617021 (8100 1975);
PAINT SKYBLUE (8100 1975);
FORCEPROP 1 LAST VALUE 0
J 2
(8075 1975);
DISPLAY 0.617021 (8075 1975);
PAINT SKYBLUE (8075 1975);
FORCEPROP 1 LAST WATTAGE 1/16W
J 2
(8150 2075);
DISPLAY 0.617021 (8150 2075);
PAINT SKYBLUE (8150 2075);
FORCEPROP 1 LAST PACK_TYPE 0402LF
J 0
(7775 2075);
DISPLAY 0.617021 (7775 2075);
PAINT SKYBLUE (7775 2075);
FORCEPROP 1 LAST LOCATION PR296
J 0
(7625 1975);
DISPLAY 0.617021 (7625 1975);
PAINT AQUA (7625 1975);
FORCEPROP 1 LASTPIN (7800 1975) $PN 1
J 0
(7812 1987);
DISPLAY 0.617021 (7812 1987);
PAINT MONO (7812 1987);
FORCEPROP 1 LASTPIN (8000 1975) $PN 2
J 0
(7962 1987);
DISPLAY 0.617021 (7962 1987);
PAINT MONO (7962 1987);
FORCEPROP 2 LAST CDS_LIB pure_quanta
J 0
(7900 1975);
DISPLAY INVISIBLE (7900 1975);
FORCEPROP 1 LAST PATH I49
J 0
(7850 2125);
DISPLAY 0.978723 (7850 2125);
PAINT WHITE (7850 2125);
DISPLAY INVISIBLE (7850 2125);
FORCEPROP 0 LAST $SEC 1
J 0
(8150 2125);
DISPLAY 0.680851 (8150 2125);
PAINT MONO (8150 2125);
DISPLAY INVISIBLE (8150 2125);
FORCEPROP 0 LAST CDS_SEC 1
J 0
(8150 2125);
DISPLAY 1.021277 (8150 2125);
DISPLAY INVISIBLE (8150 2125);
FORCEADD OFFPAGE..1
(3850 -425);
FORCEPROP 2 LAST $XR6 290 
J 0
(2878 -425);
DISPLAY 0.638298 (2878 -425);
PAINT MONO (2878 -425);
FORCEPROP 2 LAST $XR5 289 
J 0
(2998 -425);
DISPLAY 0.638298 (2998 -425);
PAINT MONO (2998 -425);
FORCEPROP 2 LAST $XR4 288 
J 0
(3118 -425);
DISPLAY 0.638298 (3118 -425);
PAINT MONO (3118 -425);
FORCEPROP 2 LAST $XR3 287 
J 0
(3238 -425);
DISPLAY 0.638298 (3238 -425);
PAINT MONO (3238 -425);
FORCEPROP 2 LAST $XR2 286 
J 0
(3358 -425);
DISPLAY 0.638298 (3358 -425);
PAINT MONO (3358 -425);
FORCEPROP 2 LAST $XR1 285 
J 0
(3478 -425);
DISPLAY 0.638298 (3478 -425);
PAINT MONO (3478 -425);
FORCEPROP 2 LAST $XR0 284 
J 0
(3598 -425);
DISPLAY 0.638298 (3598 -425);
PAINT MONO (3598 -425);
FORCEPROP 1 LAST COMMENT_BODY TRUE
J 0
(3975 -525);
DISPLAY 0.872340 (3975 -525);
PAINT GREEN (3975 -525);
DISPLAY INVISIBLE (3975 -525);
FORCEPROP 1 LAST OFFPAGE TRUE
J 0
(4175 -550);
DISPLAY 0.872340 (4175 -550);
PAINT GREEN (4175 -550);
DISPLAY INVISIBLE (4175 -550);
FORCEPROP 2 LAST CDS_LIB standard
J 0
(3850 -425);
DISPLAY INVISIBLE (3850 -425);
FORCEPROP 2 LAST PATH I5
J 0
(3600 -375);
DISPLAY 1.021277 (3600 -375);
DISPLAY INVISIBLE (3600 -375);
FORCEADD Q_CAP..1
(6925 3400);
FORCEPROP 1 LAST PART_NUMBER CH6223MEA01
J 0
(6975 3250);
DISPLAY 0.617021 (6975 3250);
PAINT BLUE (6975 3250);
DISPLAY INVISIBLE (6975 3250);
FORCEPROP 1 LAST MATERIAL X6S
J 0
(6975 3350);
DISPLAY 0.617021 (6975 3350);
PAINT SKYBLUE (6975 3350);
FORCEPROP 1 LAST TOLERANCE 20%
J 0
(6975 3400);
DISPLAY 0.617021 (6975 3400);
PAINT SKYBLUE (6975 3400);
FORCEPROP 1 LAST VALUE 22UF
J 0
(6975 3500);
DISPLAY 0.617021 (6975 3500);
PAINT SKYBLUE (6975 3500);
FORCEPROP 1 LAST VOLTAGE 16V
J 0
(6975 3450);
DISPLAY 0.617021 (6975 3450);
PAINT SKYBLUE (6975 3450);
FORCEPROP 1 LAST PACK_TYPE C0805
J 0
(6975 3300);
DISPLAY 0.617021 (6975 3300);
PAINT SKYBLUE (6975 3300);
FORCEPROP 1 LAST LOCATION PC512_P1_5
J 0
(6975 3550);
DISPLAY 0.617021 (6975 3550);
PAINT AQUA (6975 3550);
FORCEPROP 1 LASTPIN (6925 3500) $PN 1
J 0
(6935 3480);
DISPLAY 0.617021 (6935 3480);
PAINT MONO (6935 3480);
FORCEPROP 1 LASTPIN (6925 3300) $PN 2
J 0
(6935 3280);
DISPLAY 0.617021 (6935 3280);
PAINT MONO (6935 3280);
FORCEPROP 2 LAST CDS_LIB pure_quanta
J 0
(6925 3400);
DISPLAY INVISIBLE (6925 3400);
FORCEPROP 1 LAST PATH I50
J 0
(6975 3550);
DISPLAY 0.978723 (6975 3550);
PAINT WHITE (6975 3550);
DISPLAY INVISIBLE (6975 3550);
FORCEPROP 1 LAST LOCATION PC512_P1_5
J 0
(6975 3600);
DISPLAY 1.021277 (6975 3600);
PAINT AQUA (6975 3600);
DISPLAY INVISIBLE (6975 3600);
FORCEPROP 0 LAST $SEC 1
J 0
(6975 3600);
DISPLAY 0.680851 (6975 3600);
PAINT MONO (6975 3600);
DISPLAY INVISIBLE (6975 3600);
FORCEPROP 0 LAST CDS_SEC 1
J 0
(6975 3600);
DISPLAY 1.021277 (6975 3600);
DISPLAY INVISIBLE (6975 3600);
FORCEADD Q_CAP..1
(7325 3400);
FORCEPROP 1 LAST PART_NUMBER CH6223MEA01
J 0
(7375 3250);
DISPLAY 0.617021 (7375 3250);
PAINT BLUE (7375 3250);
DISPLAY INVISIBLE (7375 3250);
FORCEPROP 1 LAST MATERIAL X6S
J 0
(7375 3350);
DISPLAY 0.617021 (7375 3350);
PAINT SKYBLUE (7375 3350);
FORCEPROP 1 LAST TOLERANCE 20%
J 0
(7375 3400);
DISPLAY 0.617021 (7375 3400);
PAINT SKYBLUE (7375 3400);
FORCEPROP 1 LAST VALUE 22UF
J 0
(7375 3500);
DISPLAY 0.617021 (7375 3500);
PAINT SKYBLUE (7375 3500);
FORCEPROP 1 LAST VOLTAGE 16V
J 0
(7375 3450);
DISPLAY 0.617021 (7375 3450);
PAINT SKYBLUE (7375 3450);
FORCEPROP 1 LAST PACK_TYPE C0805
J 0
(7375 3300);
DISPLAY 0.617021 (7375 3300);
PAINT SKYBLUE (7375 3300);
FORCEPROP 1 LAST LOCATION PC514_P1_5
J 0
(7375 3550);
DISPLAY 0.617021 (7375 3550);
PAINT AQUA (7375 3550);
FORCEPROP 1 LASTPIN (7325 3500) $PN 1
J 0
(7335 3480);
DISPLAY 0.617021 (7335 3480);
PAINT MONO (7335 3480);
FORCEPROP 1 LASTPIN (7325 3300) $PN 2
J 0
(7335 3280);
DISPLAY 0.617021 (7335 3280);
PAINT MONO (7335 3280);
FORCEPROP 2 LAST CDS_LIB pure_quanta
J 0
(7325 3400);
DISPLAY INVISIBLE (7325 3400);
FORCEPROP 1 LAST PATH I51
J 0
(7375 3550);
DISPLAY 0.978723 (7375 3550);
PAINT WHITE (7375 3550);
DISPLAY INVISIBLE (7375 3550);
FORCEPROP 1 LAST LOCATION PC514_P1_5
J 0
(7375 3600);
DISPLAY 1.021277 (7375 3600);
PAINT AQUA (7375 3600);
DISPLAY INVISIBLE (7375 3600);
FORCEPROP 0 LAST $SEC 1
J 0
(7375 3600);
DISPLAY 0.680851 (7375 3600);
PAINT MONO (7375 3600);
DISPLAY INVISIBLE (7375 3600);
FORCEPROP 0 LAST CDS_SEC 1
J 0
(7375 3600);
DISPLAY 1.021277 (7375 3600);
DISPLAY INVISIBLE (7375 3600);
FORCEADD Q_CAP..1
(7700 3400);
FORCEPROP 1 LAST PART_NUMBER CH6223MEA01
J 0
(7750 3250);
DISPLAY 0.617021 (7750 3250);
PAINT BLUE (7750 3250);
DISPLAY INVISIBLE (7750 3250);
FORCEPROP 1 LAST MATERIAL X6S
J 0
(7750 3350);
DISPLAY 0.617021 (7750 3350);
PAINT SKYBLUE (7750 3350);
FORCEPROP 1 LAST TOLERANCE 20%
J 0
(7750 3400);
DISPLAY 0.617021 (7750 3400);
PAINT SKYBLUE (7750 3400);
FORCEPROP 1 LAST VALUE 22UF
J 0
(7750 3500);
DISPLAY 0.617021 (7750 3500);
PAINT SKYBLUE (7750 3500);
FORCEPROP 1 LAST VOLTAGE 16V
J 0
(7750 3450);
DISPLAY 0.617021 (7750 3450);
PAINT SKYBLUE (7750 3450);
FORCEPROP 1 LAST PACK_TYPE C0805
J 0
(7750 3300);
DISPLAY 0.617021 (7750 3300);
PAINT SKYBLUE (7750 3300);
FORCEPROP 1 LAST LOCATION PC516_P1_5
J 0
(7750 3550);
DISPLAY 0.617021 (7750 3550);
PAINT AQUA (7750 3550);
FORCEPROP 1 LASTPIN (7700 3500) $PN 1
J 0
(7710 3480);
DISPLAY 0.617021 (7710 3480);
PAINT MONO (7710 3480);
FORCEPROP 1 LASTPIN (7700 3300) $PN 2
J 0
(7710 3280);
DISPLAY 0.617021 (7710 3280);
PAINT MONO (7710 3280);
FORCEPROP 2 LAST CDS_LIB pure_quanta
J 0
(7700 3400);
DISPLAY INVISIBLE (7700 3400);
FORCEPROP 1 LAST PATH I52
J 0
(7750 3550);
DISPLAY 0.978723 (7750 3550);
PAINT WHITE (7750 3550);
DISPLAY INVISIBLE (7750 3550);
FORCEPROP 1 LAST LOCATION PC516_P1_5
J 0
(7750 3600);
DISPLAY 1.021277 (7750 3600);
PAINT AQUA (7750 3600);
DISPLAY INVISIBLE (7750 3600);
FORCEPROP 0 LAST $SEC 1
J 0
(7750 3600);
DISPLAY 0.680851 (7750 3600);
PAINT MONO (7750 3600);
DISPLAY INVISIBLE (7750 3600);
FORCEPROP 0 LAST CDS_SEC 1
J 0
(7750 3600);
DISPLAY 1.021277 (7750 3600);
DISPLAY INVISIBLE (7750 3600);
FORCEADD OFFPAGE..3
(9000 -575);
FORCEPROP 2 LAST $XR0 288 
J 0
(9214 -575);
DISPLAY 0.638298 (9214 -575);
PAINT MONO (9214 -575);
FORCEPROP 1 LAST COMMENT_BODY TRUE
J 0
(8950 -675);
DISPLAY 0.872340 (8950 -675);
PAINT GREEN (8950 -675);
DISPLAY INVISIBLE (8950 -675);
FORCEPROP 1 LAST OFFPAGE TRUE
J 0
(9325 -700);
DISPLAY 0.872340 (9325 -700);
PAINT GREEN (9325 -700);
DISPLAY INVISIBLE (9325 -700);
FORCEPROP 2 LAST CDS_LIB standard
J 0
(9000 -575);
DISPLAY INVISIBLE (9000 -575);
FORCEPROP 2 LAST PATH I53
J 0
(9225 -525);
DISPLAY 1.021277 (9225 -525);
DISPLAY INVISIBLE (9225 -525);
FORCEADD Q_CAP..1
(9675 -525);
FORCEPROP 1 LAST PART_NUMBER CH622KMEA03
J 0
(9725 -700);
DISPLAY 0.617021 (9725 -700);
PAINT BLUE (9725 -700);
DISPLAY INVISIBLE (9725 -700);
FORCEPROP 1 LAST PACK_TYPE C0805
J 0
(9725 -650);
DISPLAY 0.617021 (9725 -650);
PAINT SKYBLUE (9725 -650);
FORCEPROP 1 LAST VOLTAGE 4V
J 0
(9725 -500);
DISPLAY 0.617021 (9725 -500);
PAINT SKYBLUE (9725 -500);
FORCEPROP 1 LAST VALUE 22UF
J 0
(9725 -450);
DISPLAY 0.617021 (9725 -450);
PAINT SKYBLUE (9725 -450);
FORCEPROP 1 LAST TOLERANCE 20%
J 0
(9725 -550);
DISPLAY 0.617021 (9725 -550);
PAINT SKYBLUE (9725 -550);
FORCEPROP 1 LAST MATERIAL X6S
J 0
(9725 -600);
DISPLAY 0.617021 (9725 -600);
PAINT SKYBLUE (9725 -600);
FORCEPROP 1 LAST LOCATION PC519_P1_6
J 0
(9725 -400);
DISPLAY 0.617021 (9725 -400);
PAINT AQUA (9725 -400);
FORCEPROP 1 LASTPIN (9675 -425) $PN 1
J 0
(9685 -445);
DISPLAY 0.617021 (9685 -445);
PAINT MONO (9685 -445);
FORCEPROP 1 LASTPIN (9675 -625) $PN 2
J 0
(9685 -645);
DISPLAY 0.617021 (9685 -645);
PAINT MONO (9685 -645);
FORCEPROP 2 LAST CDS_LIB pure_quanta
J 0
(9675 -525);
DISPLAY INVISIBLE (9675 -525);
FORCEPROP 1 LAST PATH I54
J 0
(9725 -375);
DISPLAY 0.978723 (9725 -375);
PAINT WHITE (9725 -375);
DISPLAY INVISIBLE (9725 -375);
FORCEPROP 1 LAST LOCATION PC519_P1_6
J 0
(9725 -350);
DISPLAY 1.021277 (9725 -350);
PAINT AQUA (9725 -350);
DISPLAY INVISIBLE (9725 -350);
FORCEPROP 0 LAST $SEC 1
J 0
(9725 -350);
DISPLAY 0.680851 (9725 -350);
PAINT MONO (9725 -350);
DISPLAY INVISIBLE (9725 -350);
FORCEPROP 0 LAST CDS_SEC 1
J 0
(9725 -350);
DISPLAY 1.021277 (9725 -350);
DISPLAY INVISIBLE (9725 -350);
FORCEADD UNIVERSAL_GND..1
(7900 150);
FORCEPROP 3 LASTPIN (7900 200) SIG_NAME GND\g
J 0
(7910 210);
DISPLAY 0.659574 (7910 210);
PAINT MONO (7910 210);
DISPLAY INVISIBLE (7910 210);
FORCEPROP 2 LAST CDS_LIB logical_power
J 0
(7900 150);
PAINT MONO (7900 150);
DISPLAY INVISIBLE (7900 150);
FORCEPROP 1 LAST HDL_POWER GND
J 1
(7925 75);
DISPLAY 0.872340 (7925 75);
PAINT GREEN (7925 75);
DISPLAY INVISIBLE (7925 75);
FORCEPROP 1 LAST PATH I55
J 0
(7975 150);
DISPLAY 0.872340 (7975 150);
PAINT AQUA (7975 150);
DISPLAY INVISIBLE (7975 150);
FORCEADD VCC15..1
(7900 950);
FORCEPROP 3 LASTPIN (7900 900) SIG_NAME SW_P12V_PVCCIN_CPU1_FLT\g
J 0
(7910 910);
DISPLAY 0.659574 (7910 910);
PAINT MONO (7910 910);
DISPLAY INVISIBLE (7910 910);
FORCEPROP 1 LAST HDL_POWER SW_P12V_PVCCIN_CPU1_FLT
J 1
(7950 1000);
DISPLAY 0.617021 (7950 1000);
PAINT GREEN (7950 1000);
FORCEPROP 2 LAST CDS_LIB logical_power
J 0
(7900 950);
DISPLAY INVISIBLE (7900 950);
FORCEPROP 1 LAST PATH I56
J 0
(7950 975);
DISPLAY 0.872340 (7950 975);
PAINT AQUA (7950 975);
DISPLAY INVISIBLE (7950 975);
FORCEADD Q_CAP..1
(10100 -525);
FORCEPROP 1 LAST PART_NUMBER CH622KMEA03
J 0
(10150 -700);
DISPLAY 0.617021 (10150 -700);
PAINT BLUE (10150 -700);
DISPLAY INVISIBLE (10150 -700);
FORCEPROP 1 LAST PACK_TYPE C0805
J 0
(10150 -650);
DISPLAY 0.617021 (10150 -650);
PAINT SKYBLUE (10150 -650);
FORCEPROP 1 LAST VOLTAGE 4V
J 0
(10150 -500);
DISPLAY 0.617021 (10150 -500);
PAINT SKYBLUE (10150 -500);
FORCEPROP 1 LAST VALUE 22UF
J 0
(10150 -450);
DISPLAY 0.617021 (10150 -450);
PAINT SKYBLUE (10150 -450);
FORCEPROP 1 LAST TOLERANCE 20%
J 0
(10150 -550);
DISPLAY 0.617021 (10150 -550);
PAINT SKYBLUE (10150 -550);
FORCEPROP 1 LAST MATERIAL X6S
J 0
(10150 -600);
DISPLAY 0.617021 (10150 -600);
PAINT SKYBLUE (10150 -600);
FORCEPROP 1 LAST LOCATION PC521_P1_6
J 0
(10150 -400);
DISPLAY 0.617021 (10150 -400);
PAINT AQUA (10150 -400);
FORCEPROP 1 LASTPIN (10100 -425) $PN 1
J 0
(10110 -445);
DISPLAY 0.617021 (10110 -445);
PAINT MONO (10110 -445);
FORCEPROP 1 LASTPIN (10100 -625) $PN 2
J 0
(10110 -645);
DISPLAY 0.617021 (10110 -645);
PAINT MONO (10110 -645);
FORCEPROP 2 LAST CDS_LIB pure_quanta
J 0
(10100 -525);
DISPLAY INVISIBLE (10100 -525);
FORCEPROP 1 LAST PATH I57
J 0
(10150 -375);
DISPLAY 0.978723 (10150 -375);
PAINT WHITE (10150 -375);
DISPLAY INVISIBLE (10150 -375);
FORCEPROP 1 LAST LOCATION PC521_P1_6
J 0
(10150 -350);
DISPLAY 1.021277 (10150 -350);
PAINT AQUA (10150 -350);
DISPLAY INVISIBLE (10150 -350);
FORCEPROP 0 LAST $SEC 1
J 0
(10150 -350);
DISPLAY 0.680851 (10150 -350);
PAINT MONO (10150 -350);
DISPLAY INVISIBLE (10150 -350);
FORCEPROP 0 LAST CDS_SEC 1
J 0
(10150 -350);
DISPLAY 1.021277 (10150 -350);
DISPLAY INVISIBLE (10150 -350);
FORCEADD UNIVERSAL_GND..1
(10400 -900);
FORCEPROP 3 LASTPIN (10400 -850) SIG_NAME GND\g
J 0
(10410 -840);
DISPLAY 0.659574 (10410 -840);
PAINT MONO (10410 -840);
DISPLAY INVISIBLE (10410 -840);
FORCEPROP 2 LAST CDS_LIB logical_power
J 0
(10400 -900);
PAINT MONO (10400 -900);
DISPLAY INVISIBLE (10400 -900);
FORCEPROP 1 LAST HDL_POWER GND
J 1
(10425 -975);
DISPLAY 0.872340 (10425 -975);
PAINT GREEN (10425 -975);
DISPLAY INVISIBLE (10425 -975);
FORCEPROP 1 LAST PATH I58
J 0
(10475 -900);
DISPLAY 0.872340 (10475 -900);
PAINT AQUA (10475 -900);
DISPLAY INVISIBLE (10475 -900);
FORCEADD VCC15..1
(10400 -125);
FORCEPROP 3 LASTPIN (10400 -175) SIG_NAME PVCCIN_CPU1\g
J 0
(10410 -165);
DISPLAY 0.659574 (10410 -165);
PAINT MONO (10410 -165);
DISPLAY INVISIBLE (10410 -165);
FORCEPROP 1 LAST HDL_POWER PVCCIN_CPU1
J 1
(10400 -75);
DISPLAY 0.617021 (10400 -75);
PAINT GREEN (10400 -75);
FORCEPROP 2 LAST CDS_LIB logical_power
J 0
(10400 -125);
DISPLAY INVISIBLE (10400 -125);
FORCEPROP 1 LAST PATH I59
J 0
(10450 -100);
DISPLAY 0.872340 (10450 -100);
PAINT AQUA (10450 -100);
DISPLAY INVISIBLE (10450 -100);
FORCEADD UNIVERSAL_GND..1
(3400 1775);
FORCEPROP 3 LASTPIN (3400 1825) SIG_NAME GND\g
J 0
(3410 1835);
DISPLAY 0.659574 (3410 1835);
PAINT MONO (3410 1835);
DISPLAY INVISIBLE (3410 1835);
FORCEPROP 2 LAST CDS_LIB logical_power
J 0
(3400 1775);
PAINT MONO (3400 1775);
DISPLAY INVISIBLE (3400 1775);
FORCEPROP 1 LAST HDL_POWER GND
J 1
(3425 1700);
DISPLAY 0.872340 (3425 1700);
PAINT GREEN (3425 1700);
DISPLAY INVISIBLE (3425 1700);
FORCEPROP 1 LAST PATH I6
J 0
(3475 1775);
DISPLAY 0.872340 (3475 1775);
PAINT AQUA (3475 1775);
DISPLAY INVISIBLE (3475 1775);
FORCEADD UNIVERSAL_GND..1
(10275 1925);
FORCEPROP 3 LASTPIN (10275 1975) SIG_NAME GND\g
J 0
(10285 1985);
DISPLAY 0.659574 (10285 1985);
PAINT MONO (10285 1985);
DISPLAY INVISIBLE (10285 1985);
FORCEPROP 2 LAST CDS_LIB logical_power
J 0
(10275 1925);
PAINT MONO (10275 1925);
DISPLAY INVISIBLE (10275 1925);
FORCEPROP 1 LAST HDL_POWER GND
J 1
(10300 1850);
DISPLAY 0.872340 (10300 1850);
PAINT GREEN (10300 1850);
DISPLAY INVISIBLE (10300 1850);
FORCEPROP 1 LAST PATH I60
J 0
(10350 1925);
DISPLAY 0.872340 (10350 1925);
PAINT AQUA (10350 1925);
DISPLAY INVISIBLE (10350 1925);
FORCEADD UNIVERSAL_GND..1
(7925 2975);
FORCEPROP 3 LASTPIN (7925 3025) SIG_NAME GND\g
J 0
(7935 3035);
DISPLAY 0.659574 (7935 3035);
PAINT MONO (7935 3035);
DISPLAY INVISIBLE (7935 3035);
FORCEPROP 2 LAST CDS_LIB logical_power
J 0
(7925 2975);
PAINT MONO (7925 2975);
DISPLAY INVISIBLE (7925 2975);
FORCEPROP 1 LAST HDL_POWER GND
J 1
(7950 2900);
DISPLAY 0.872340 (7950 2900);
PAINT GREEN (7950 2900);
DISPLAY INVISIBLE (7950 2900);
FORCEPROP 1 LAST PATH I61
J 0
(8000 2975);
DISPLAY 0.872340 (8000 2975);
PAINT AQUA (8000 2975);
DISPLAY INVISIBLE (8000 2975);
FORCEADD OFFPAGE..3
(8750 2250);
FORCEPROP 2 LAST $XR0 286 
J 0
(8964 2250);
DISPLAY 0.638298 (8964 2250);
PAINT MONO (8964 2250);
FORCEPROP 1 LAST COMMENT_BODY TRUE
J 0
(8700 2150);
DISPLAY 0.872340 (8700 2150);
PAINT GREEN (8700 2150);
DISPLAY INVISIBLE (8700 2150);
FORCEPROP 1 LAST OFFPAGE TRUE
J 0
(9075 2125);
DISPLAY 0.872340 (9075 2125);
PAINT GREEN (9075 2125);
DISPLAY INVISIBLE (9075 2125);
FORCEPROP 2 LAST CDS_LIB standard
J 0
(8750 2250);
DISPLAY INVISIBLE (8750 2250);
FORCEPROP 2 LAST PATH I62
J 0
(8975 2300);
DISPLAY 1.021277 (8975 2300);
DISPLAY INVISIBLE (8975 2300);
FORCEADD VCC15..1
(7925 3775);
FORCEPROP 3 LASTPIN (7925 3725) SIG_NAME SW_P12V_PVCCIN_CPU1_FLT\g
J 0
(7935 3735);
DISPLAY 0.659574 (7935 3735);
PAINT MONO (7935 3735);
DISPLAY INVISIBLE (7935 3735);
FORCEPROP 1 LAST HDL_POWER SW_P12V_PVCCIN_CPU1_FLT
J 1
(7975 3825);
DISPLAY 0.617021 (7975 3825);
PAINT GREEN (7975 3825);
FORCEPROP 2 LAST CDS_LIB logical_power
J 0
(7925 3775);
DISPLAY INVISIBLE (7925 3775);
FORCEPROP 1 LAST PATH I63
J 0
(7975 3800);
DISPLAY 0.872340 (7975 3800);
PAINT AQUA (7975 3800);
DISPLAY INVISIBLE (7975 3800);
FORCEADD Q_CAP..1
(9550 2300);
FORCEPROP 1 LAST PART_NUMBER CH622KMEA03
J 0
(9600 2125);
DISPLAY 0.617021 (9600 2125);
PAINT BLUE (9600 2125);
DISPLAY INVISIBLE (9600 2125);
FORCEPROP 1 LAST PACK_TYPE C0805
J 0
(9600 2175);
DISPLAY 0.617021 (9600 2175);
PAINT SKYBLUE (9600 2175);
FORCEPROP 1 LAST VOLTAGE 4V
J 0
(9600 2325);
DISPLAY 0.617021 (9600 2325);
PAINT SKYBLUE (9600 2325);
FORCEPROP 1 LAST VALUE 22UF
J 0
(9600 2375);
DISPLAY 0.617021 (9600 2375);
PAINT SKYBLUE (9600 2375);
FORCEPROP 1 LAST TOLERANCE 20%
J 0
(9600 2275);
DISPLAY 0.617021 (9600 2275);
PAINT SKYBLUE (9600 2275);
FORCEPROP 1 LAST MATERIAL X6S
J 0
(9600 2225);
DISPLAY 0.617021 (9600 2225);
PAINT SKYBLUE (9600 2225);
FORCEPROP 1 LAST LOCATION PC520_P1_5
J 0
(9600 2425);
DISPLAY 0.617021 (9600 2425);
PAINT AQUA (9600 2425);
FORCEPROP 1 LASTPIN (9550 2400) $PN 1
J 0
(9560 2380);
DISPLAY 0.617021 (9560 2380);
PAINT MONO (9560 2380);
FORCEPROP 1 LASTPIN (9550 2200) $PN 2
J 0
(9560 2180);
DISPLAY 0.617021 (9560 2180);
PAINT MONO (9560 2180);
FORCEPROP 2 LAST CDS_LIB pure_quanta
J 0
(9550 2300);
DISPLAY INVISIBLE (9550 2300);
FORCEPROP 1 LAST PATH I64
J 0
(9600 2450);
DISPLAY 0.978723 (9600 2450);
PAINT WHITE (9600 2450);
DISPLAY INVISIBLE (9600 2450);
FORCEPROP 1 LAST LOCATION PC520_P1_5
J 0
(9600 2475);
DISPLAY 1.021277 (9600 2475);
PAINT AQUA (9600 2475);
DISPLAY INVISIBLE (9600 2475);
FORCEPROP 0 LAST $SEC 1
J 0
(9600 2475);
DISPLAY 0.680851 (9600 2475);
PAINT MONO (9600 2475);
DISPLAY INVISIBLE (9600 2475);
FORCEPROP 0 LAST CDS_SEC 1
J 0
(9600 2475);
DISPLAY 1.021277 (9600 2475);
DISPLAY INVISIBLE (9600 2475);
FORCEADD Q_CAP..1
(9975 2300);
FORCEPROP 1 LAST PART_NUMBER CH622KMEA03
J 0
(10025 2125);
DISPLAY 0.617021 (10025 2125);
PAINT BLUE (10025 2125);
DISPLAY INVISIBLE (10025 2125);
FORCEPROP 1 LAST PACK_TYPE C0805
J 0
(10025 2175);
DISPLAY 0.617021 (10025 2175);
PAINT SKYBLUE (10025 2175);
FORCEPROP 1 LAST VOLTAGE 4V
J 0
(10025 2325);
DISPLAY 0.617021 (10025 2325);
PAINT SKYBLUE (10025 2325);
FORCEPROP 1 LAST VALUE 22UF
J 0
(10025 2375);
DISPLAY 0.617021 (10025 2375);
PAINT SKYBLUE (10025 2375);
FORCEPROP 1 LAST TOLERANCE 20%
J 0
(10025 2275);
DISPLAY 0.617021 (10025 2275);
PAINT SKYBLUE (10025 2275);
FORCEPROP 1 LAST MATERIAL X6S
J 0
(10025 2225);
DISPLAY 0.617021 (10025 2225);
PAINT SKYBLUE (10025 2225);
FORCEPROP 1 LAST LOCATION PC522_P1_5
J 0
(10025 2425);
DISPLAY 0.617021 (10025 2425);
PAINT AQUA (10025 2425);
FORCEPROP 1 LASTPIN (9975 2400) $PN 1
J 0
(9985 2380);
DISPLAY 0.617021 (9985 2380);
PAINT MONO (9985 2380);
FORCEPROP 1 LASTPIN (9975 2200) $PN 2
J 0
(9985 2180);
DISPLAY 0.617021 (9985 2180);
PAINT MONO (9985 2180);
FORCEPROP 2 LAST CDS_LIB pure_quanta
J 0
(9975 2300);
DISPLAY INVISIBLE (9975 2300);
FORCEPROP 1 LAST PATH I65
J 0
(10025 2450);
DISPLAY 0.978723 (10025 2450);
PAINT WHITE (10025 2450);
DISPLAY INVISIBLE (10025 2450);
FORCEPROP 1 LAST LOCATION PC522_P1_5
J 0
(10025 2475);
DISPLAY 1.021277 (10025 2475);
PAINT AQUA (10025 2475);
DISPLAY INVISIBLE (10025 2475);
FORCEPROP 0 LAST $SEC 1
J 0
(10025 2475);
DISPLAY 0.680851 (10025 2475);
PAINT MONO (10025 2475);
DISPLAY INVISIBLE (10025 2475);
FORCEPROP 0 LAST CDS_SEC 1
J 0
(10025 2475);
DISPLAY 1.021277 (10025 2475);
DISPLAY INVISIBLE (10025 2475);
FORCEADD VCC15..1
(10275 2700);
FORCEPROP 3 LASTPIN (10275 2650) SIG_NAME PVCCIN_CPU1\g
J 0
(10285 2660);
DISPLAY 0.659574 (10285 2660);
PAINT MONO (10285 2660);
DISPLAY INVISIBLE (10285 2660);
FORCEPROP 1 LAST HDL_POWER PVCCIN_CPU1
J 1
(10275 2750);
DISPLAY 0.617021 (10275 2750);
PAINT GREEN (10275 2750);
FORCEPROP 2 LAST CDS_LIB logical_power
J 0
(10275 2700);
DISPLAY INVISIBLE (10275 2700);
FORCEPROP 1 LAST PATH I66
J 0
(10325 2725);
DISPLAY 0.872340 (10325 2725);
PAINT AQUA (10325 2725);
DISPLAY INVISIBLE (10325 2725);
FORCEADD Q_RES..2
R 2
(3400 2000);
FORCEPROP 1 LAST PART_NUMBER CS28872FB01
J 2
(3350 1875);
DISPLAY 0.617021 (3350 1875);
PAINT BLUE (3350 1875);
DISPLAY INVISIBLE (3350 1875);
FORCEPROP 1 LAST WATTAGE 1/16W
J 2
(3350 1975);
DISPLAY 0.617021 (3350 1975);
PAINT SKYBLUE (3350 1975);
FORCEPROP 1 LAST TOLERANCE 1%
J 2
(3345 2025);
DISPLAY 0.617021 (3345 2025);
PAINT SKYBLUE (3345 2025);
FORCEPROP 1 LAST VALUE 8.87K
J 2
(3345 2075);
DISPLAY 0.617021 (3345 2075);
PAINT SKYBLUE (3345 2075);
FORCEPROP 1 LAST MATERIAL EMPTY
J 2
(3350 1925);
DISPLAY 0.617021 (3350 1925);
PAINT RED (3350 1925);
FORCEPROP 1 LAST PACK_TYPE 0402LF
J 2
(3350 1825);
DISPLAY 0.617021 (3350 1825);
PAINT SKYBLUE (3350 1825);
FORCEPROP 1 LAST LOCATION PR292
J 2
(3355 2125);
DISPLAY 0.617021 (3355 2125);
PAINT AQUA (3355 2125);
FORCEPROP 1 LASTPIN (3400 2100) $PN 1
J 2
(3395 2062);
DISPLAY 0.617021 (3395 2062);
PAINT MONO (3395 2062);
FORCEPROP 1 LASTPIN (3400 1900) $PN 2
J 2
(3395 1910);
DISPLAY 0.617021 (3395 1910);
PAINT MONO (3395 1910);
FORCEPROP 2 LAST CDS_LIB pure_quanta
J 2
(3400 2000);
DISPLAY INVISIBLE (3400 2000);
FORCEPROP 1 LAST PATH I7
J 2
(3350 2175);
DISPLAY 0.978723 (3350 2175);
PAINT WHITE (3350 2175);
DISPLAY INVISIBLE (3350 2175);
FORCEPROP 1 LAST LOCATION PR292
J 2
(3350 2175);
DISPLAY 1.021277 (3350 2175);
PAINT AQUA (3350 2175);
DISPLAY INVISIBLE (3350 2175);
FORCEPROP 0 LAST $SEC 1
J 2
(3350 2175);
DISPLAY 0.680851 (3350 2175);
PAINT MONO (3350 2175);
DISPLAY INVISIBLE (3350 2175);
FORCEPROP 0 LAST CDS_SEC 1
J 2
(3350 2175);
DISPLAY 1.021277 (3350 2175);
DISPLAY INVISIBLE (3350 2175);
FORCEADD OFFPAGE..1
(3875 1900);
FORCEPROP 2 LAST $XR0 284 
J 0
(3449 1900);
DISPLAY 0.638298 (3449 1900);
PAINT MONO (3449 1900);
FORCEPROP 1 LAST COMMENT_BODY TRUE
J 0
(4000 1800);
DISPLAY 0.872340 (4000 1800);
PAINT GREEN (4000 1800);
DISPLAY INVISIBLE (4000 1800);
FORCEPROP 1 LAST OFFPAGE TRUE
J 0
(4200 1775);
DISPLAY 0.872340 (4200 1775);
PAINT GREEN (4200 1775);
DISPLAY INVISIBLE (4200 1775);
FORCEPROP 2 LAST CDS_LIB standard
J 0
(3875 1900);
DISPLAY INVISIBLE (3875 1900);
FORCEPROP 2 LAST PATH I8
J 0
(3625 1950);
DISPLAY 1.021277 (3625 1950);
DISPLAY INVISIBLE (3625 1950);
FORCEADD UNIVERSAL_GND..1
(3300 2225);
FORCEPROP 3 LASTPIN (3300 2275) SIG_NAME GND\g
J 0
(3310 2285);
DISPLAY 0.659574 (3310 2285);
PAINT MONO (3310 2285);
DISPLAY INVISIBLE (3310 2285);
FORCEPROP 2 LAST CDS_LIB logical_power
J 0
(3300 2225);
PAINT MONO (3300 2225);
DISPLAY INVISIBLE (3300 2225);
FORCEPROP 1 LAST HDL_POWER GND
J 1
(3325 2150);
DISPLAY 0.872340 (3325 2150);
PAINT GREEN (3325 2150);
DISPLAY INVISIBLE (3325 2150);
FORCEPROP 1 LAST PATH I9
J 0
(3375 2225);
DISPLAY 0.872340 (3375 2225);
PAINT AQUA (3375 2225);
DISPLAY INVISIBLE (3375 2225);
FORCEADD DNS..1
(3375 -850);
PAINT RED (3375 -850);
FORCEPROP 2 LAST CDS_LIB mstr_misc
J 0
(3375 -850);
PAINT MONO (3375 -850);
DISPLAY INVISIBLE (3375 -850);
FORCEPROP 1 LAST COMMENT_BODY TRUE
R 1
J 0
(3450 -1075);
DISPLAY 0.872340 (3450 -1075);
PAINT GREEN (3450 -1075);
DISPLAY INVISIBLE (3450 -1075);
FORCEADD DNS..1
(3400 1975);
PAINT RED (3400 1975);
FORCEPROP 2 LAST CDS_LIB mstr_misc
J 0
(3400 1975);
PAINT MONO (3400 1975);
DISPLAY INVISIBLE (3400 1975);
FORCEPROP 1 LAST COMMENT_BODY TRUE
R 1
J 0
(3475 1750);
DISPLAY 0.872340 (3475 1750);
PAINT GREEN (3475 1750);
DISPLAY INVISIBLE (3475 1750);
FORCEADD QUANTA_TITLE_BLOCK_C..1
(11150 -1800);
FORCEPROP 0 LAST CDS_CON_LAST_MODIFIED Fri Aug 25 14:04:57 2023
J 0
(9265 -1785);
DISPLAY INVISIBLE (9265 -1785);
FORCEPROP 1 LAST CUSTOM_TXT_CDS <CON_LAST_MODIFIED>
J 0
(9265 -1785);
DISPLAY 0.978723 (9265 -1785);
FORCEPROP 2 LAST CUSTOM_TXT_CDS <XR_PAGE_TITLE>
J 0
(3260 3450);
DISPLAY 0.638298 (3260 3450);
PAINT PINK (3260 3450);
DISPLAY INVISIBLE (3260 3450);
FORCEPROP 1 LAST CUSTOM_TXT_CDS <NAME_2>
J 0
(7975 -1750);
FORCEPROP 1 LAST CUSTOM_TXT_CDS <NAME_1>
J 0
(7975 -1625);
FORCEPROP 1 LAST CUSTOM_TXT_CDS <Q_NUMBER>
J 0
(9747 -1697);
DISPLAY 1.212766 (9747 -1697);
FORCEPROP 1 LAST CUSTOM_TXT_CDS <Q_PROJ>
J 0
(8768 -1698);
DISPLAY 1.212766 (8768 -1698);
FORCEPROP 1 LAST CUSTOM_TXT_CDS <Q_REV>
J 0
(10966 -1697);
DISPLAY 1.212766 (10966 -1697);
FORCEPROP 1 LAST CUSTOM_TXT_CDS <CON_PAGE_NUM> OF <CON_TOTAL_PAGES>
J 0
(10704 -1782);
DISPLAY 0.978723 (10704 -1782);
FORCEPROP 1 LAST Q_TITLE VCCIN CPU1 VR PHASE 5&6 (4/7)
J 0
(1850 -1750);
DISPLAY 2.446809 (1850 -1750);
PAINT GREEN (1850 -1750);
FORCEPROP 1 LAST Q_DEPT 
J 1
(7387 -1751);
DISPLAY 1.957447 (7387 -1751);
PAINT GREEN (7387 -1751);
FORCEPROP 2 LAST CDS_XR_PAGE_TITLE CR-287 : @S9S_MB_2U_LIB.S9S_MB_2U(SCH_1):PAGE287
J 0
(3260 3450);
DISPLAY 0.638298 (3260 3450);
PAINT PINK (3260 3450);
DISPLAY INVISIBLE (3260 3450);
FORCEPROP 1 LAST COMMENT_BODY TRUE
J 0
(11162 -1813);
DISPLAY 0.978723 (11162 -1813);
PAINT GREEN (11162 -1813);
DISPLAY INVISIBLE (11162 -1813);
FORCEPROP 2 LAST CDS_LIB pure_quanta
J 0
(11150 -1800);
DISPLAY INVISIBLE (11150 -1800);
FORCEPROP 1 LAST CDS_LMAN_SYM_OUTLINE -9475,6775,100,-125
J 0
(11150 -1800);
DISPLAY 0.468085 (11150 -1800);
PAINT GREEN (11150 -1800);
DISPLAY INVISIBLE (11150 -1800);
FORCEPROP 2 LAST PAGE_BORDER TRUE
J 0
(3260 3450);
DISPLAY 0.638298 (3260 3450);
PAINT PINK (3260 3450);
DISPLAY INVISIBLE (3260 3450);
WIRE 16 -1 (3775 900)(3775 950);
WIRE 16 -1 (4200 900)(3775 900);
WIRE 16 -1 (3775 775)(3775 900);
WIRE 16 -1 (3800 3725)(3800 3775);
WIRE 16 -1 (4225 3725)(3800 3725);
WIRE 16 -1 (3800 3600)(3800 3725);
WIRE 16 -1 (7900 900)(7900 825);
WIRE 16 -1 (10400 -175)(10400 -325);
WIRE 16 -1 (7925 3725)(7925 3650);
WIRE 16 -1 (10275 2650)(10275 2500);
WIRE 16 -1 (3375 -925)(3375 -1000);
WIRE 16 -1 (3275 -525)(3275 -550);
WIRE 16 -1 (3275 -525)(4000 -525);
WIRE 16 -1 (3400 1900)(3400 1825);
WIRE 16 -1 (3300 2300)(3300 2275);
WIRE 16 -1 (3300 2300)(4025 2300);
WIRE 16 -1 (3775 75)(3775 -25);
WIRE 16 -1 (4200 575)(4200 500);
WIRE 16 -1 (5950 -925)(5950 -1000);
WIRE 16 -1 (5950 -875)(5950 -925);
WIRE 16 -1 (5700 -925)(5950 -925);
WIRE 16 -1 (5975 1900)(5975 1825);
WIRE 16 -1 (5975 1950)(5975 1900);
WIRE 16 -1 (5725 1900)(5975 1900);
WIRE 16 -1 (3800 2900)(3800 2800);
WIRE 16 -1 (4225 3400)(4225 3325);
WIRE 16 -1 (7900 200)(7900 325);
WIRE 16 -1 (10400 -850)(10400 -750);
WIRE 16 -1 (10275 1975)(10275 2075);
WIRE 16 -1 (7925 3025)(7925 3150);
WIRE 16 -1 (4225 3725)(4225 3600);
WIRE 16 -1 (4800 3725)(4225 3725);
WIRE 16 -1 (4800 3150)(4800 3725);
WIRE 16 -1 (4875 3150)(4800 3150);
WIRE 16 -1 (8000 1975)(9375 1975);
WIRE 16 -1 (9375 2500)(8175 2500);
WIRE 16 -1 (9375 1975)(9375 2500);
WIRE 16 -1 (9550 2500)(9375 2500);
WIRE 16 -1 (9550 2500)(9550 2400);
WIRE 16 -1 (9550 2500)(9975 2500);
WIRE 16 -1 (9975 2400)(9975 2500);
WIRE 16 -1 (10275 2500)(9975 2500);
WIRE 16 -1 (9550 2075)(9550 2200);
WIRE 16 -1 (9975 2075)(9550 2075);
WIRE 16 -1 (9975 2200)(9975 2075);
WIRE 16 -1 (10275 2075)(9975 2075);
WIRE 16 -1 (8175 2250)(8700 2250);
FORCEPROP 2 LAST SIG_NAME IND_P1_CPL4
J 0
(8290 2260);
DISPLAY 0.617021 (8290 2260);
WIRE 16 -1 (9675 -750)(9675 -625);
WIRE 16 -1 (10100 -750)(9675 -750);
WIRE 16 -1 (10100 -750)(10100 -625);
WIRE 16 -1 (10400 -750)(10100 -750);
WIRE 16 -1 (9525 -900)(7950 -900);
WIRE 16 -1 (8200 -325)(9525 -325);
WIRE 16 -1 (9525 -900)(9525 -325);
WIRE 16 -1 (9675 -325)(9525 -325);
WIRE 16 -1 (9675 -325)(9675 -425);
WIRE 16 -1 (9675 -325)(10100 -325);
WIRE 16 -1 (10100 -325)(10100 -425);
WIRE 16 -1 (10100 -325)(10400 -325);
WIRE 16 -1 (8200 -575)(8950 -575);
FORCEPROP 2 LAST SIG_NAME IND_P1_CPL7
J 0
(8290 -565);
DISPLAY 0.617021 (8290 -565);
WIRE 16 -1 (6100 475)(6100 325);
WIRE 16 -1 (6100 325)(6500 325);
WIRE 16 -1 (6500 475)(6500 325);
WIRE 16 -1 (6900 325)(6500 325);
WIRE 16 -1 (6900 475)(6900 325);
WIRE 16 -1 (6900 325)(7300 325);
WIRE 16 -1 (7300 475)(7300 325);
WIRE 16 -1 (7300 325)(7675 325);
WIRE 16 -1 (7675 475)(7675 325);
WIRE 16 -1 (7900 325)(7675 325);
WIRE 16 -1 (5700 275)(5875 275);
WIRE 16 -1 (5875 275)(5875 325);
WIRE 16 -1 (5700 325)(5875 325);
WIRE 16 -1 (5875 825)(5875 325);
WIRE 16 -1 (5875 825)(6100 825);
WIRE 16 -1 (6100 675)(6100 825);
WIRE 16 -1 (6100 825)(6500 825);
WIRE 16 -1 (6500 675)(6500 825);
WIRE 16 -1 (6500 825)(6900 825);
WIRE 16 -1 (6900 825)(6900 675);
WIRE 16 -1 (6900 825)(7300 825);
WIRE 16 -1 (7300 675)(7300 825);
WIRE 16 -1 (7300 825)(7675 825);
WIRE 16 -1 (7675 675)(7675 825);
WIRE 16 -1 (7900 825)(7675 825);
WIRE 16 -1 (6125 3300)(6125 3150);
WIRE 16 -1 (6125 3150)(6525 3150);
WIRE 16 -1 (6525 3300)(6525 3150);
WIRE 16 -1 (6925 3150)(6525 3150);
WIRE 16 -1 (6925 3300)(6925 3150);
WIRE 16 -1 (6925 3150)(7325 3150);
WIRE 16 -1 (7325 3300)(7325 3150);
WIRE 16 -1 (7325 3150)(7700 3150);
WIRE 16 -1 (7700 3300)(7700 3150);
WIRE 16 -1 (7925 3150)(7700 3150);
WIRE 16 -1 (5725 3100)(5900 3100);
WIRE 16 -1 (5725 3150)(5900 3150);
WIRE 16 -1 (5900 3100)(5900 3150);
WIRE 16 -1 (5900 3650)(5900 3150);
WIRE 16 -1 (6125 3500)(6125 3650);
WIRE 16 -1 (5900 3650)(6125 3650);
WIRE 16 -1 (6125 3650)(6525 3650);
WIRE 16 -1 (6525 3500)(6525 3650);
WIRE 16 -1 (6525 3650)(6925 3650);
WIRE 16 -1 (6925 3650)(6925 3500);
WIRE 16 -1 (6925 3650)(7325 3650);
WIRE 16 -1 (7325 3500)(7325 3650);
WIRE 16 -1 (7325 3650)(7700 3650);
WIRE 16 -1 (7700 3500)(7700 3650);
WIRE 16 -1 (7925 3650)(7700 3650);
WIRE 16 -1 (6850 2250)(7375 2250);
FORCEPROP 2 LAST SIG_NAME IND_P1_CPL5
J 0
(6915 2260);
DISPLAY 0.617021 (6915 2260);
WIRE 16 -1 (6675 2950)(7300 2950);
FORCEPROP 2 LAST SIG_NAME SW_PVCCIN_CPU1_BOOT5_R
J 0
(6865 2960);
DISPLAY 0.617021 (6865 2960);
WIRE 16 -1 (7300 2950)(7300 2875);
WIRE 16 -1 (5725 2850)(5875 2850);
WIRE 16 -1 (5875 2850)(5875 2950);
FORCEPROP 2 LAST SIG_NAME SW_PVCCIN_CPU1_BOOT5
J 0
(5765 2960);
DISPLAY 0.617021 (5765 2960);
WIRE 16 -1 (5875 2950)(6475 2950);
FORCEPROP 0 LAST CDS_PHYS_NET_NAME SW_PVCCIN_CPU1_BOOT5
J 0
(5915 2979);
PAINT MONO (5915 2979);
DISPLAY INVISIBLE (5915 2979);
WIRE 16 -1 (6225 1975)(7800 1975);
FORCEPROP 2 LAST SIG_NAME PVCCIN_CPU1_VOS5
J 0
(6340 1985);
DISPLAY 0.617021 (6340 1985);
WIRE 16 -1 (5725 2250)(6225 2250);
WIRE 16 -1 (6225 2250)(6225 1975);
WIRE 16 -1 (5725 2500)(7375 2500);
FORCEPROP 2 LAST SIG_NAME SW_PVCCIN_CPU1_SW5
J 0
(5915 2510);
DISPLAY 0.617021 (5915 2510);
WIRE 16 -1 (5725 2600)(7300 2600);
FORCEPROP 0 LAST CDS_PHYS_NET_NAME SW_PVCCIN_CPU1_BOOTR5
J 0
(5915 2640);
PAINT MONO (5915 2640);
DISPLAY INVISIBLE (5915 2640);
FORCEPROP 2 LAST SIG_NAME SW_PVCCIN_CPU1_BOOTR5
J 0
(5915 2610);
DISPLAY 0.617021 (5915 2610);
WIRE 16 -1 (7300 2600)(7300 2675);
WIRE 16 -1 (5725 1950)(5975 1950);
WIRE 16 -1 (5725 2000)(5975 2000);
WIRE 16 -1 (5975 2000)(5975 1950);
WIRE 16 -1 (5975 2050)(5975 2000);
WIRE 16 -1 (5725 2050)(5975 2050);
WIRE 16 -1 (3800 3250)(3800 3100);
WIRE 16 -1 (3800 3400)(3800 3250);
WIRE 16 -1 (3800 3250)(4200 3250);
WIRE 16 -1 (4200 2850)(4200 3250);
WIRE 16 -1 (4200 2850)(4775 2850);
FORCEPROP 2 LAST SIG_NAME PVCCIN_CPU1_VDD5
J 0
(4240 2860);
DISPLAY 0.617021 (4240 2860);
WIRE 16 -1 (4775 2850)(4875 2850);
WIRE 16 -1 (4775 2650)(4775 2850);
WIRE 16 -1 (4875 2650)(4775 2650);
WIRE 16 -1 (4875 2000)(3925 2000);
FORCEPROP 2 LAST SIG_NAME PVCCIN_CPU1_ATSEN
J 0
(4040 2010);
DISPLAY 0.617021 (4040 2010);
WIRE 16 -1 (4875 2500)(3925 2500);
FORCEPROP 2 LAST SIG_NAME PVCCIN_CPU1_IMON5
J 0
(4040 2510);
DISPLAY 0.617021 (4040 2510);
WIRE 16 -1 (4775 2300)(4225 2300);
WIRE 16 -1 (3925 2400)(4775 2400);
FORCEPROP 2 LAST SIG_NAME PVCCIN_CPU1_VREF
J 0
(4040 2410);
DISPLAY 0.617021 (4040 2410);
WIRE 16 -1 (4775 2400)(4775 2300);
FORCEPROP 0 LAST CDS_PHYS_NET_NAME PVCCIN_CPU1_VREF
J 0
(4775 2325);
PAINT MONO (4775 2325);
DISPLAY INVISIBLE (4775 2325);
WIRE 16 -1 (4775 2400)(4875 2400);
WIRE 16 -1 (6650 125)(7275 125);
FORCEPROP 2 LAST SIG_NAME SW_PVCCIN_CPU1_BOOT6_R
J 0
(6840 135);
DISPLAY 0.617021 (6840 135);
WIRE 16 -1 (7275 125)(7275 50);
WIRE 16 -1 (5700 25)(5850 25);
WIRE 16 -1 (5850 25)(5850 125);
FORCEPROP 2 LAST SIG_NAME SW_PVCCIN_CPU1_BOOT6
J 0
(5740 135);
DISPLAY 0.617021 (5740 135);
WIRE 16 -1 (5850 125)(6450 125);
FORCEPROP 0 LAST CDS_PHYS_NET_NAME SW_PVCCIN_CPU1_BOOT6
J 0
(5890 154);
PAINT MONO (5890 154);
DISPLAY INVISIBLE (5890 154);
WIRE 16 -1 (6600 -575)(7400 -575);
FORCEPROP 2 LAST SIG_NAME IND_P1_CPL6
J 0
(6740 -565);
DISPLAY 0.617021 (6740 -565);
WIRE 16 -1 (5700 -600)(5700 -575);
WIRE 16 -1 (5700 -575)(6100 -575);
WIRE 16 -1 (6100 -575)(6100 -900);
WIRE 16 -1 (7750 -900)(6100 -900);
FORCEPROP 2 LAST SIG_NAME PVCCIN_CPU1_VOS6
J 0
(6315 -890);
DISPLAY 0.617021 (6315 -890);
WIRE 16 -1 (5700 -225)(7275 -225);
FORCEPROP 0 LAST CDS_PHYS_NET_NAME SW_PVCCIN_CPU1_BOOTR6
J 0
(5890 -185);
PAINT MONO (5890 -185);
DISPLAY INVISIBLE (5890 -185);
FORCEPROP 2 LAST SIG_NAME SW_PVCCIN_CPU1_BOOTR6
J 0
(5890 -215);
DISPLAY 0.617021 (5890 -215);
WIRE 16 -1 (7275 -225)(7275 -150);
WIRE 16 -1 (5700 -325)(7400 -325);
FORCEPROP 2 LAST SIG_NAME SW_PVCCIN_CPU1_SW6
J 0
(5890 -315);
DISPLAY 0.617021 (5890 -315);
WIRE 16 -1 (5700 -875)(5950 -875);
WIRE 16 -1 (5700 -825)(5950 -825);
WIRE 16 -1 (5950 -825)(5950 -875);
WIRE 16 -1 (5950 -775)(5950 -825);
WIRE 16 -1 (5700 -775)(5950 -775);
WIRE 16 -1 (4200 900)(4200 775);
WIRE 16 -1 (4775 900)(4200 900);
WIRE 16 -1 (4775 325)(4775 900);
WIRE 16 -1 (4850 325)(4775 325);
WIRE 16 -1 (4875 1900)(3925 1900);
FORCEPROP 2 LAST SIG_NAME PVCCIN_CPU1_PWM5
J 0
(4040 1910);
DISPLAY 0.617021 (4040 1910);
WIRE 16 -1 (3775 425)(3775 275);
WIRE 16 -1 (3775 575)(3775 425);
WIRE 16 -1 (3775 425)(4175 425);
WIRE 16 -1 (4175 25)(4175 425);
WIRE 16 -1 (4750 25)(4175 25);
FORCEPROP 2 LAST SIG_NAME PVCCIN_CPU1_VDD6
J 0
(4215 35);
DISPLAY 0.617021 (4215 35);
WIRE 16 -1 (4850 25)(4750 25);
WIRE 16 -1 (4750 -175)(4750 25);
WIRE 16 -1 (4850 -175)(4750 -175);
WIRE 16 -1 (4850 -825)(3900 -825);
FORCEPROP 2 LAST SIG_NAME PVCCIN_CPU1_ATSEN
J 0
(4015 -815);
DISPLAY 0.617021 (4015 -815);
WIRE 16 -1 (4850 -325)(3900 -325);
FORCEPROP 2 LAST SIG_NAME PVCCIN_CPU1_IMON6
J 0
(4015 -315);
DISPLAY 0.617021 (4015 -315);
WIRE 16 -1 (4850 -925)(3900 -925);
FORCEPROP 2 LAST SIG_NAME PVCCIN_CPU1_PWM6
J 0
(4015 -915);
DISPLAY 0.617021 (4015 -915);
WIRE 16 -1 (4750 -525)(4200 -525);
WIRE 16 -1 (3900 -425)(4750 -425);
FORCEPROP 2 LAST SIG_NAME PVCCIN_CPU1_VREF
J 0
(4015 -415);
DISPLAY 0.617021 (4015 -415);
WIRE 16 -1 (4750 -425)(4750 -525);
FORCEPROP 0 LAST CDS_PHYS_NET_NAME PVCCIN_CPU1_VREF
J 0
(4750 -500);
PAINT MONO (4750 -500);
DISPLAY INVISIBLE (4750 -500);
WIRE 16 -1 (4750 -425)(4850 -425);
WIRE 16 -1 (3400 2200)(3400 2100);
WIRE 16 -1 (3400 2200)(4875 2200);
FORCEPROP 2 LAST SIG_NAME PVCCIN_CPU1_LSET5
J 0
(4040 2210);
DISPLAY 0.617021 (4040 2210);
WIRE 16 -1 (3375 -625)(3375 -725);
WIRE 16 -1 (3375 -625)(4850 -625);
FORCEPROP 2 LAST SIG_NAME PVCCIN_CPU1_LSET6
J 0
(4015 -615);
DISPLAY 0.617021 (4015 -615);
DOT 1 (4750 -425);
DOT 1 (3775 425);
DOT 1 (3775 900);
DOT 1 (4200 900);
DOT 1 (4750 25);
DOT 1 (5950 -925);
DOT 1 (5950 -875);
DOT 1 (5950 -825);
DOT 1 (5875 325);
DOT 1 (6100 825);
DOT 1 (6500 325);
DOT 1 (6500 825);
DOT 1 (5975 1900);
DOT 1 (6900 325);
DOT 1 (7300 325);
DOT 1 (6900 825);
DOT 1 (7300 825);
DOT 1 (7675 325);
DOT 1 (7675 825);
DOT 1 (5975 1950);
DOT 1 (3800 3250);
DOT 1 (3800 3725);
DOT 1 (4225 3725);
DOT 1 (4775 2400);
DOT 1 (4775 2850);
DOT 1 (5975 2000);
DOT 1 (5900 3150);
DOT 1 (6125 3650);
DOT 1 (6525 3150);
DOT 1 (6525 3650);
DOT 1 (6925 3150);
DOT 1 (6925 3650);
DOT 1 (7325 3150);
DOT 1 (7700 3150);
DOT 1 (7325 3650);
DOT 1 (7700 3650);
DOT 1 (9525 -325);
DOT 1 (9675 -325);
DOT 1 (10100 -750);
DOT 1 (10100 -325);
DOT 1 (9375 2500);
DOT 1 (9550 2500);
DOT 1 (9975 2075);
DOT 1 (9975 2500);
FORCENOTE
PVCCIN_CPU1_PHASE6
(4900 775) 0;
DISPLAY LEFT (4900 775);
DISPLAY 1.021277 (4900 775);
PAINT WHITE (4900 775);
FORCENOTE
PVCCIN_CPU1_PHASE5
(4925 3600) 0;
DISPLAY LEFT (4925 3600);
DISPLAY 1.021277 (4925 3600);
PAINT WHITE (4925 3600);
FORCENOTE
11.0*7.5*12.5
(8150 150) 0;
DISPLAY LEFT (8150 150);
DISPLAY 1.021277 (8150 150);
FORCENOTE
ISAT=70A@100C
(8150 75) 0;
DISPLAY LEFT (8150 75);
DISPLAY 1.021277 (8150 75);
FORCENOTE
PGL6303.151HLT 
(8150 225) 0;
DISPLAY LEFT (8150 225);
DISPLAY 1.021277 (8150 225);
FORCENOTE
DCR=2-3,0.27M OHM
(8150 -75) 0;
DISPLAY LEFT (8150 -75);
DISPLAY 1.021277 (8150 -75);
FORCENOTE
DCR=1-4,0.105M OHM
(8150 0) 0;
DISPLAY LEFT (8150 0);
DISPLAY 1.021277 (8150 0);
FORCENOTE
ISAT=70A@100C
(8100 2775) 0;
DISPLAY LEFT (8100 2775);
DISPLAY 1.021277 (8100 2775);
FORCENOTE
PGL6303.151HLT 
(8100 2925) 0;
DISPLAY LEFT (8100 2925);
DISPLAY 1.021277 (8100 2925);
FORCENOTE
11.0*7.5*12.5
(8100 2850) 0;
DISPLAY LEFT (8100 2850);
DISPLAY 1.021277 (8100 2850);
FORCENOTE
DCR=1-4,0.105M OHM
(8100 2700) 0;
DISPLAY LEFT (8100 2700);
DISPLAY 1.021277 (8100 2700);
FORCENOTE
DCR=2-3,0.27M OHM
(8100 2625) 0;
DISPLAY LEFT (8100 2625);
DISPLAY 1.021277 (8100 2625);
QUIT
